FILE_TYPE = MACRO_DRAWING;
SET COLOR_WIRE YELLOW;
SET COLOR_PROP ORANGE;
SET COLOR_DOT WHITE;
SET COLOR_ARC YELLOW;
SET COLOR_BODY GREEN;
SET COLOR_NOTE PURPLE;
SET PROP_DISPLAY VALUE;
SET PAGE_NUMBER P163;
FORCEADD Q_RES..2
(525 350);
FORCEPROP 1 LAST PART_NUMBER CS00002JB13
J 0
(600 300);
DISPLAY 0.404255 (600 300);
DISPLAY INVISIBLE (600 300);
FORCEPROP 1 LAST WATTAGE 1/16W
J 0
(600 350);
DISPLAY 0.404255 (600 350);
FORCEPROP 1 LAST VALUE 0
J 0
(600 400);
DISPLAY 0.404255 (600 400);
FORCEPROP 1 LAST MATERIAL CHIP
J 0
(600 325);
DISPLAY 0.404255 (600 325);
FORCEPROP 1 LAST PACK_TYPE 0402LF
J 0
(600 275);
DISPLAY 0.404255 (600 275);
FORCEPROP 1 LAST TOLERANCE 5%
J 0
(600 375);
DISPLAY 0.404255 (600 375);
FORCEPROP 1 LAST $LOCATION R3620
J 0
(600 425);
DISPLAY 0.638298 (600 425);
FORCEPROP 1 LASTPIN (525 450) $PN 1
J 0
(530 412);
DISPLAY 0.787234 (530 412);
PAINT MONO (530 412);
FORCEPROP 1 LASTPIN (525 250) $PN 2
J 0
(530 260);
DISPLAY 0.787234 (530 260);
PAINT MONO (530 260);
FORCEPROP 2 LAST CDS_LIB pure_quanta
J 0
(525 350);
DISPLAY INVISIBLE (525 350);
FORCEPROP 1 LAST PATH I100
J 0
(575 525);
DISPLAY 0.978723 (575 525);
PAINT WHITE (575 525);
DISPLAY INVISIBLE (575 525);
FORCEPROP 0 LAST CDS_LOCATION R3620
J 0
(600 475);
DISPLAY 1.021277 (600 475);
DISPLAY INVISIBLE (600 475);
FORCEPROP 0 LAST $SEC 1
J 0
(600 475);
DISPLAY 0.680851 (600 475);
PAINT MONO (600 475);
DISPLAY INVISIBLE (600 475);
FORCEPROP 0 LAST CDS_SEC 1
J 0
(600 475);
DISPLAY 1.021277 (600 475);
DISPLAY INVISIBLE (600 475);
FORCEADD Q_RES..1
(100 125);
FORCEPROP 1 LAST PART_NUMBER CS03322FB03
J 0
(-50 175);
DISPLAY 0.510638 (-50 175);
DISPLAY INVISIBLE (-50 175);
FORCEPROP 1 LAST TOLERANCE 1%
J 0
(325 125);
DISPLAY 0.510638 (325 125);
FORCEPROP 1 LAST MATERIAL CHIP
J 0
(400 125);
DISPLAY 0.510638 (400 125);
FORCEPROP 1 LAST WATTAGE 1/16W
J 2
(225 200);
DISPLAY 0.510638 (225 200);
FORCEPROP 1 LAST PACK_TYPE 0402LF
J 0
(-50 200);
DISPLAY 0.510638 (-50 200);
FORCEPROP 1 LAST VALUE 33.2
J 2
(300 125);
DISPLAY 0.510638 (300 125);
FORCEPROP 1 LAST $LOCATION R3568
J 0
(-150 125);
DISPLAY 0.787234 (-150 125);
FORCEPROP 1 LASTPIN (0 125) $PN 1
J 0
(12 137);
DISPLAY 0.787234 (12 137);
FORCEPROP 1 LASTPIN (200 125) $PN 2
J 0
(162 137);
DISPLAY 0.787234 (162 137);
FORCEPROP 2 LAST CDS_LIB pure_quanta
J 0
(100 125);
PAINT MONO (100 125);
DISPLAY INVISIBLE (100 125);
FORCEPROP 1 LAST PATH I101
J 0
(50 275);
DISPLAY 0.978723 (50 275);
PAINT WHITE (50 275);
DISPLAY INVISIBLE (50 275);
FORCEPROP 2 LAST CDS_LOCATION R3568
J 0
(50 325);
DISPLAY 1.021277 (50 325);
DISPLAY INVISIBLE (50 325);
FORCEPROP 2 LAST $SEC 1
J 0
(50 325);
DISPLAY 0.680851 (50 325);
PAINT MONO (50 325);
DISPLAY INVISIBLE (50 325);
FORCEPROP 2 LAST CDS_SEC 1
J 0
(50 325);
DISPLAY 1.021277 (50 325);
DISPLAY INVISIBLE (50 325);
FORCEADD Q_RES..1
(100 75);
FORCEPROP 1 LAST PART_NUMBER CS03322FB03
J 0
(-25 125);
DISPLAY 0.638298 (-25 125);
DISPLAY INVISIBLE (-25 125);
FORCEPROP 1 LAST MATERIAL CHIP
J 0
(400 75);
DISPLAY 0.510638 (400 75);
FORCEPROP 1 LAST TOLERANCE 1%
J 0
(325 75);
DISPLAY 0.510638 (325 75);
FORCEPROP 1 LAST VALUE 33.2
J 2
(300 75);
DISPLAY 0.510638 (300 75);
FORCEPROP 1 LAST $LOCATION R3569
J 0
(-150 75);
DISPLAY 0.787234 (-150 75);
FORCEPROP 1 LASTPIN (0 75) $PN 1
J 0
(12 87);
DISPLAY 0.787234 (12 87);
FORCEPROP 1 LASTPIN (200 75) $PN 2
J 0
(162 87);
DISPLAY 0.787234 (162 87);
FORCEPROP 1 LAST WATTAGE 1/16W
J 2
(300 175);
DISPLAY 0.638298 (300 175);
DISPLAY INVISIBLE (300 175);
FORCEPROP 1 LAST PACK_TYPE 0402LF
J 0
(450 75);
DISPLAY 0.638298 (450 75);
DISPLAY INVISIBLE (450 75);
FORCEPROP 2 LAST CDS_LIB pure_quanta
J 0
(100 75);
PAINT MONO (100 75);
DISPLAY INVISIBLE (100 75);
FORCEPROP 1 LAST PATH I102
J 0
(50 225);
DISPLAY 0.978723 (50 225);
PAINT WHITE (50 225);
DISPLAY INVISIBLE (50 225);
FORCEPROP 2 LAST CDS_LOCATION R3569
J 0
(50 275);
DISPLAY 1.021277 (50 275);
DISPLAY INVISIBLE (50 275);
FORCEPROP 2 LAST $SEC 1
J 0
(50 275);
DISPLAY 0.680851 (50 275);
PAINT MONO (50 275);
DISPLAY INVISIBLE (50 275);
FORCEPROP 2 LAST CDS_SEC 1
J 0
(50 275);
DISPLAY 1.021277 (50 275);
DISPLAY INVISIBLE (50 275);
FORCEADD Q_RES..1
(-525 600);
FORCEPROP 1 LAST PART_NUMBER CS24702FB06
J 0
(-950 600);
DISPLAY 0.510638 (-950 600);
DISPLAY INVISIBLE (-950 600);
FORCEPROP 1 LAST TOLERANCE 1%
J 0
(-200 600);
DISPLAY 0.510638 (-200 600);
FORCEPROP 1 LAST VALUE 4.7K
J 2
(-325 600);
DISPLAY 0.510638 (-325 600);
FORCEPROP 1 LAST WATTAGE 1/16W
J 2
(-200 600);
DISPLAY 0.510638 (-200 600);
FORCEPROP 1 LAST PACK_TYPE 0402LF
J 0
(-50 600);
DISPLAY 0.510638 (-50 600);
FORCEPROP 1 LAST MATERIAL CHIP
J 0
(-150 600);
DISPLAY 0.510638 (-150 600);
FORCEPROP 1 LAST $LOCATION R3608
J 0
(-650 600);
DISPLAY 0.638298 (-650 600);
FORCEPROP 1 LASTPIN (-625 600) $PN 1
J 0
(-613 612);
DISPLAY 0.787234 (-613 612);
PAINT MONO (-613 612);
FORCEPROP 1 LASTPIN (-425 600) $PN 2
J 0
(-463 612);
DISPLAY 0.787234 (-463 612);
PAINT MONO (-463 612);
FORCEPROP 2 LAST CDS_LIB pure_quanta
J 0
(-525 600);
DISPLAY INVISIBLE (-525 600);
FORCEPROP 1 LAST PATH I103
J 0
(-575 750);
DISPLAY 0.978723 (-575 750);
PAINT WHITE (-575 750);
DISPLAY INVISIBLE (-575 750);
FORCEPROP 0 LAST CDS_LOCATION R3608
J 0
(-650 650);
DISPLAY 1.021277 (-650 650);
DISPLAY INVISIBLE (-650 650);
FORCEPROP 0 LAST $SEC 1
J 0
(-650 650);
DISPLAY 0.680851 (-650 650);
PAINT MONO (-650 650);
DISPLAY INVISIBLE (-650 650);
FORCEPROP 0 LAST CDS_SEC 1
J 0
(-650 650);
DISPLAY 1.021277 (-650 650);
DISPLAY INVISIBLE (-650 650);
FORCEADD Q_RES..1
(-525 525);
FORCEPROP 1 LAST PART_NUMBER CS24702FB06
J 0
(-950 525);
DISPLAY 0.510638 (-950 525);
DISPLAY INVISIBLE (-950 525);
FORCEPROP 1 LAST PACK_TYPE 0402LF
J 0
(-50 525);
DISPLAY 0.510638 (-50 525);
FORCEPROP 1 LAST TOLERANCE 1%
J 0
(-200 525);
DISPLAY 0.510638 (-200 525);
FORCEPROP 1 LAST MATERIAL EMPTY
J 0
(-150 525);
DISPLAY 0.510638 (-150 525);
PAINT RED (-150 525);
FORCEPROP 1 LAST VALUE 4.7K
J 2
(-325 525);
DISPLAY 0.510638 (-325 525);
FORCEPROP 1 LAST WATTAGE 1/16W
J 2
(-200 525);
DISPLAY 0.510638 (-200 525);
FORCEPROP 1 LAST $LOCATION R3609
J 0
(-650 525);
DISPLAY 0.638298 (-650 525);
FORCEPROP 1 LASTPIN (-625 525) $PN 1
J 0
(-613 537);
DISPLAY 0.787234 (-613 537);
PAINT MONO (-613 537);
FORCEPROP 1 LASTPIN (-425 525) $PN 2
J 0
(-463 537);
DISPLAY 0.787234 (-463 537);
PAINT MONO (-463 537);
FORCEPROP 2 LAST CDS_LIB pure_quanta
J 0
(-525 525);
DISPLAY INVISIBLE (-525 525);
FORCEPROP 1 LAST PATH I104
J 0
(-575 675);
DISPLAY 0.978723 (-575 675);
PAINT WHITE (-575 675);
DISPLAY INVISIBLE (-575 675);
FORCEPROP 0 LAST CDS_LOCATION R3609
J 0
(-650 575);
DISPLAY 1.021277 (-650 575);
DISPLAY INVISIBLE (-650 575);
FORCEPROP 0 LAST $SEC 1
J 0
(-650 575);
DISPLAY 0.680851 (-650 575);
PAINT MONO (-650 575);
DISPLAY INVISIBLE (-650 575);
FORCEPROP 0 LAST CDS_SEC 1
J 0
(-650 575);
DISPLAY 1.021277 (-650 575);
DISPLAY INVISIBLE (-650 575);
FORCEADD UNIVERSAL_GND..1
(-950 400);
FORCEPROP 3 LASTPIN (-950 450) SIG_NAME GND\g
J 0
(-940 460);
DISPLAY 0.659574 (-940 460);
PAINT MONO (-940 460);
DISPLAY INVISIBLE (-940 460);
FORCEPROP 1 LAST HDL_POWER GND
J 1
(-925 325);
DISPLAY 0.872340 (-925 325);
PAINT GREEN (-925 325);
DISPLAY INVISIBLE (-925 325);
FORCEPROP 2 LAST CDS_LIB logical_power
J 0
(-950 400);
DISPLAY INVISIBLE (-950 400);
FORCEPROP 1 LAST PATH I105
J 0
(-875 400);
DISPLAY 0.872340 (-875 400);
PAINT AQUA (-875 400);
DISPLAY INVISIBLE (-875 400);
FORCEADD OFFPAGE..1
(-1075 125);
FORCEPROP 2 LAST $XR0 232 
J 0
(-1357 125);
DISPLAY 0.638298 (-1357 125);
PAINT MONO (-1357 125);
FORCEPROP 2 LAST CDS_LIB standard
J 0
(-1075 125);
DISPLAY INVISIBLE (-1075 125);
FORCEPROP 1 LAST OFFPAGE TRUE
J 0
(-750 0);
DISPLAY 0.872340 (-750 0);
DISPLAY INVISIBLE (-750 0);
FORCEPROP 1 LAST COMMENT_BODY TRUE
J 0
(-950 25);
DISPLAY 0.872340 (-950 25);
PAINT GREEN (-950 25);
DISPLAY INVISIBLE (-950 25);
FORCEPROP 2 LAST PATH I106
J 0
(-1325 175);
DISPLAY 1.021277 (-1325 175);
DISPLAY INVISIBLE (-1325 175);
FORCEADD UNIVERSAL_GND..1
(2250 -525);
FORCEPROP 3 LASTPIN (2250 -475) SIG_NAME GND\g
J 0
(2260 -465);
DISPLAY 0.659574 (2260 -465);
PAINT MONO (2260 -465);
DISPLAY INVISIBLE (2260 -465);
FORCEPROP 2 LAST CDS_LIB logical_power
J 0
(2250 -525);
DISPLAY INVISIBLE (2250 -525);
FORCEPROP 1 LAST HDL_POWER GND
J 1
(2275 -600);
DISPLAY 0.872340 (2275 -600);
PAINT GREEN (2275 -600);
DISPLAY INVISIBLE (2275 -600);
FORCEPROP 1 LAST PATH I107
J 0
(2325 -525);
DISPLAY 0.872340 (2325 -525);
PAINT AQUA (2325 -525);
DISPLAY INVISIBLE (2325 -525);
FORCEADD Q_CAP..1
(500 -625);
FORCEPROP 1 LAST PART_NUMBER CH4104K1B00
J 0
(550 -675);
DISPLAY 0.510638 (550 -675);
DISPLAY INVISIBLE (550 -675);
FORCEPROP 1 LAST VOLTAGE 25V
J 0
(550 -600);
DISPLAY 0.510638 (550 -600);
FORCEPROP 1 LAST TOLERANCE 10%
J 0
(550 -625);
DISPLAY 0.510638 (550 -625);
FORCEPROP 1 LAST MATERIAL X7R
J 0
(550 -650);
DISPLAY 0.510638 (550 -650);
FORCEPROP 1 LAST PACK_TYPE 0402
J 0
(550 -700);
DISPLAY 0.510638 (550 -700);
FORCEPROP 1 LAST VALUE 0.1UF
J 0
(550 -575);
DISPLAY 0.510638 (550 -575);
FORCEPROP 1 LAST $LOCATION C2020
J 0
(550 -525);
DISPLAY 0.978723 (550 -525);
FORCEPROP 1 LASTPIN (500 -525) $PN 1
J 0
(510 -545);
DISPLAY 0.787234 (510 -545);
PAINT MONO (510 -545);
FORCEPROP 1 LASTPIN (500 -725) $PN 2
J 0
(510 -745);
DISPLAY 0.787234 (510 -745);
PAINT MONO (510 -745);
FORCEPROP 2 LAST CDS_LIB pure_quanta
J 0
(500 -625);
DISPLAY INVISIBLE (500 -625);
FORCEPROP 1 LAST PATH I108
J 0
(550 -475);
DISPLAY 0.978723 (550 -475);
PAINT WHITE (550 -475);
DISPLAY INVISIBLE (550 -475);
FORCEPROP 0 LAST CDS_LOCATION C2020
J 0
(550 -475);
DISPLAY 1.021277 (550 -475);
DISPLAY INVISIBLE (550 -475);
FORCEPROP 0 LAST $SEC 1
J 0
(550 -475);
DISPLAY 0.680851 (550 -475);
PAINT MONO (550 -475);
DISPLAY INVISIBLE (550 -475);
FORCEPROP 0 LAST CDS_SEC 1
J 0
(550 -475);
DISPLAY 1.021277 (550 -475);
DISPLAY INVISIBLE (550 -475);
FORCEADD Q_RES..1
(150 -475);
FORCEPROP 1 LAST PART_NUMBER CS01002FB07
J 0
(0 -425);
DISPLAY 0.638298 (0 -425);
DISPLAY INVISIBLE (0 -425);
FORCEPROP 1 LAST WATTAGE 1/16W
J 2
(150 -575);
DISPLAY 0.638298 (150 -575);
FORCEPROP 1 LAST VALUE 10
J 2
(100 -525);
DISPLAY 0.638298 (100 -525);
FORCEPROP 1 LAST TOLERANCE 1%
J 0
(200 -525);
DISPLAY 0.638298 (200 -525);
FORCEPROP 1 LAST MATERIAL CHIP
J 0
(175 -575);
DISPLAY 0.638298 (175 -575);
FORCEPROP 1 LAST PACK_TYPE 0402LF
J 0
(275 -525);
DISPLAY 0.638298 (275 -525);
FORCEPROP 1 LAST $LOCATION R3570
J 0
(-100 -475);
DISPLAY 0.638298 (-100 -475);
FORCEPROP 1 LASTPIN (50 -475) $PN 1
J 0
(62 -463);
DISPLAY 0.787234 (62 -463);
PAINT MONO (62 -463);
FORCEPROP 1 LASTPIN (250 -475) $PN 2
J 0
(212 -463);
DISPLAY 0.787234 (212 -463);
PAINT MONO (212 -463);
FORCEPROP 2 LAST CDS_LIB pure_quanta
J 0
(150 -475);
DISPLAY INVISIBLE (150 -475);
FORCEPROP 1 LAST PATH I109
J 0
(100 -325);
DISPLAY 0.978723 (100 -325);
PAINT WHITE (100 -325);
DISPLAY INVISIBLE (100 -325);
FORCEPROP 0 LAST CDS_LOCATION R3570
J 0
(0 -375);
DISPLAY 1.021277 (0 -375);
DISPLAY INVISIBLE (0 -375);
FORCEPROP 0 LAST $SEC 1
J 0
(0 -375);
DISPLAY 0.680851 (0 -375);
PAINT MONO (0 -375);
DISPLAY INVISIBLE (0 -375);
FORCEPROP 0 LAST CDS_SEC 1
J 0
(0 -375);
DISPLAY 1.021277 (0 -375);
DISPLAY INVISIBLE (0 -375);
FORCEADD Q_RES..1
(150 -750);
FORCEPROP 1 LAST PART_NUMBER CS01002FB07
J 0
(0 -700);
DISPLAY 0.638298 (0 -700);
DISPLAY INVISIBLE (0 -700);
FORCEPROP 1 LAST WATTAGE 1/16W
J 2
(150 -850);
DISPLAY 0.638298 (150 -850);
FORCEPROP 1 LAST VALUE 10
J 2
(100 -800);
DISPLAY 0.638298 (100 -800);
FORCEPROP 1 LAST PACK_TYPE 0402LF
J 0
(275 -800);
DISPLAY 0.638298 (275 -800);
FORCEPROP 1 LAST TOLERANCE 1%
J 0
(200 -800);
DISPLAY 0.638298 (200 -800);
FORCEPROP 1 LAST MATERIAL CHIP
J 0
(175 -850);
DISPLAY 0.638298 (175 -850);
FORCEPROP 1 LAST $LOCATION R3571
J 0
(-100 -750);
DISPLAY 0.638298 (-100 -750);
FORCEPROP 1 LASTPIN (50 -750) $PN 1
J 0
(62 -738);
DISPLAY 0.787234 (62 -738);
PAINT MONO (62 -738);
FORCEPROP 1 LASTPIN (250 -750) $PN 2
J 0
(212 -738);
DISPLAY 0.787234 (212 -738);
PAINT MONO (212 -738);
FORCEPROP 2 LAST CDS_LIB pure_quanta
J 0
(150 -750);
DISPLAY INVISIBLE (150 -750);
FORCEPROP 1 LAST PATH I110
J 0
(100 -600);
DISPLAY 0.978723 (100 -600);
PAINT WHITE (100 -600);
DISPLAY INVISIBLE (100 -600);
FORCEPROP 0 LAST CDS_LOCATION R3571
J 0
(0 -650);
DISPLAY 1.021277 (0 -650);
DISPLAY INVISIBLE (0 -650);
FORCEPROP 0 LAST $SEC 1
J 0
(0 -650);
DISPLAY 0.680851 (0 -650);
PAINT MONO (0 -650);
DISPLAY INVISIBLE (0 -650);
FORCEPROP 0 LAST CDS_SEC 1
J 0
(0 -650);
DISPLAY 1.021277 (0 -650);
DISPLAY INVISIBLE (0 -650);
FORCEADD OFFPAGE..3
R 2
(-1075 75);
FORCEPROP 2 LAST $XR0 232 
J 0
(-1355 75);
DISPLAY 0.638298 (-1355 75);
PAINT MONO (-1355 75);
FORCEPROP 1 LAST OFFPAGE TRUE
J 2
(-1400 -50);
DISPLAY 0.872340 (-1400 -50);
DISPLAY INVISIBLE (-1400 -50);
FORCEPROP 1 LAST COMMENT_BODY TRUE
J 2
(-1025 -25);
DISPLAY 0.872340 (-1025 -25);
PAINT GREEN (-1025 -25);
DISPLAY INVISIBLE (-1025 -25);
FORCEPROP 2 LAST CDS_LIB standard
J 2
(-1075 75);
PAINT MONO (-1075 75);
DISPLAY INVISIBLE (-1075 75);
FORCEPROP 2 LAST PATH I111
J 0
(-1350 125);
DISPLAY 1.021277 (-1350 125);
DISPLAY INVISIBLE (-1350 125);
FORCEADD UNIVERSAL_POWER..1
(-1250 -125);
FORCEPROP 3 LASTPIN (-1250 -175) SIG_NAME P3V3_OCP_V3_2_R\g
J 0
(-1240 -165);
DISPLAY 0.659574 (-1240 -165);
PAINT MONO (-1240 -165);
DISPLAY INVISIBLE (-1240 -165);
FORCEPROP 1 LAST HDL_POWER P3V3_OCP_V3_2_R
J 1
(-1250 -75);
DISPLAY 0.872340 (-1250 -75);
PAINT GREEN (-1250 -75);
FORCEPROP 2 LAST CDS_LIB logical_power
J 0
(-1250 -125);
DISPLAY INVISIBLE (-1250 -125);
FORCEPROP 1 LAST PATH I112
J 0
(-1200 -100);
DISPLAY 0.872340 (-1200 -100);
PAINT AQUA (-1200 -100);
DISPLAY INVISIBLE (-1200 -100);
FORCEADD UNIVERSAL_POWER..1
(-1400 625);
FORCEPROP 3 LASTPIN (-1400 575) SIG_NAME P3V3_OCP_V3_2_R\g
J 0
(-1390 585);
DISPLAY 0.659574 (-1390 585);
PAINT MONO (-1390 585);
DISPLAY INVISIBLE (-1390 585);
FORCEPROP 1 LAST HDL_POWER P3V3_OCP_V3_2_R
J 1
(-1400 675);
DISPLAY 0.872340 (-1400 675);
PAINT GREEN (-1400 675);
FORCEPROP 2 LAST CDS_LIB logical_power
J 0
(-1400 625);
DISPLAY INVISIBLE (-1400 625);
FORCEPROP 1 LAST PATH I113
J 0
(-1350 650);
DISPLAY 0.872340 (-1350 650);
PAINT AQUA (-1350 650);
DISPLAY INVISIBLE (-1350 650);
FORCEADD Q_CAP..1
(-1650 300);
FORCEPROP 1 LAST PART_NUMBER CH4104K1B00
J 0
(-1600 150);
DISPLAY 0.808511 (-1600 150);
DISPLAY INVISIBLE (-1600 150);
FORCEPROP 1 LAST MATERIAL X7R
J 0
(-1600 200);
DISPLAY 0.638298 (-1600 200);
FORCEPROP 1 LAST PACK_TYPE 0402
J 0
(-1600 150);
DISPLAY 0.638298 (-1600 150);
FORCEPROP 1 LAST TOLERANCE 10%
J 0
(-1600 250);
DISPLAY 0.638298 (-1600 250);
FORCEPROP 1 LAST VOLTAGE 25V
J 0
(-1600 300);
DISPLAY 0.638298 (-1600 300);
FORCEPROP 1 LAST VALUE 0.1UF
J 0
(-1600 350);
DISPLAY 0.638298 (-1600 350);
FORCEPROP 1 LAST $LOCATION C2017
J 0
(-1600 400);
DISPLAY 0.978723 (-1600 400);
FORCEPROP 1 LASTPIN (-1650 400) $PN 1
J 0
(-1640 380);
DISPLAY 0.787234 (-1640 380);
PAINT MONO (-1640 380);
FORCEPROP 1 LASTPIN (-1650 200) $PN 2
J 0
(-1640 180);
DISPLAY 0.787234 (-1640 180);
PAINT MONO (-1640 180);
FORCEPROP 2 LAST CDS_LIB pure_quanta
J 0
(-1650 300);
DISPLAY INVISIBLE (-1650 300);
FORCEPROP 1 LAST PATH I114
J 0
(-1600 450);
DISPLAY 0.978723 (-1600 450);
PAINT WHITE (-1600 450);
DISPLAY INVISIBLE (-1600 450);
FORCEPROP 0 LAST CDS_LOCATION C2017
J 0
(-1600 450);
DISPLAY 1.021277 (-1600 450);
DISPLAY INVISIBLE (-1600 450);
FORCEPROP 0 LAST $SEC 1
J 0
(-1600 450);
DISPLAY 0.680851 (-1600 450);
PAINT MONO (-1600 450);
DISPLAY INVISIBLE (-1600 450);
FORCEPROP 0 LAST CDS_SEC 1
J 0
(-1600 450);
DISPLAY 1.021277 (-1600 450);
DISPLAY INVISIBLE (-1600 450);
FORCEADD UNIVERSAL_GND..1
(-1650 25);
FORCEPROP 3 LASTPIN (-1650 75) SIG_NAME GND\g
J 0
(-1640 85);
DISPLAY 0.659574 (-1640 85);
PAINT MONO (-1640 85);
DISPLAY INVISIBLE (-1640 85);
FORCEPROP 2 LAST CDS_LIB logical_power
J 0
(-1650 25);
DISPLAY INVISIBLE (-1650 25);
FORCEPROP 1 LAST HDL_POWER GND
J 1
(-1625 -50);
DISPLAY 0.872340 (-1625 -50);
PAINT GREEN (-1625 -50);
DISPLAY INVISIBLE (-1625 -50);
FORCEPROP 1 LAST PATH I115
J 0
(-1575 25);
DISPLAY 0.872340 (-1575 25);
PAINT AQUA (-1575 25);
DISPLAY INVISIBLE (-1575 25);
FORCEADD UNIVERSAL_POWER..1
(-2325 -125);
FORCEPROP 3 LASTPIN (-2325 -175) SIG_NAME P3V3_OCP_V3_2\g
J 0
(-2315 -165);
DISPLAY 0.659574 (-2315 -165);
PAINT MONO (-2315 -165);
DISPLAY INVISIBLE (-2315 -165);
FORCEPROP 1 LAST HDL_POWER P3V3_OCP_V3_2
J 1
(-2325 -75);
DISPLAY 0.872340 (-2325 -75);
PAINT GREEN (-2325 -75);
FORCEPROP 2 LAST CDS_LIB logical_power
J 0
(-2325 -125);
DISPLAY INVISIBLE (-2325 -125);
FORCEPROP 1 LAST PATH I117
J 0
(-2275 -100);
DISPLAY 0.872340 (-2275 -100);
PAINT AQUA (-2275 -100);
DISPLAY INVISIBLE (-2275 -100);
FORCEADD UNIVERSAL_POWER..1
(-2625 -4375);
FORCEPROP 3 LASTPIN (-2625 -4425) SIG_NAME P12V_SCM\g
J 0
(-2615 -4415);
DISPLAY 0.659574 (-2615 -4415);
PAINT MONO (-2615 -4415);
DISPLAY INVISIBLE (-2615 -4415);
FORCEPROP 1 LAST HDL_POWER P12V_SCM
J 1
(-2625 -4325);
DISPLAY 0.872340 (-2625 -4325);
PAINT GREEN (-2625 -4325);
FORCEPROP 1 LAST PATH I118
J 0
(-2575 -4350);
DISPLAY 0.872340 (-2575 -4350);
PAINT AQUA (-2575 -4350);
DISPLAY INVISIBLE (-2575 -4350);
FORCEPROP 2 LAST CDS_LIB logical_power
J 0
(-2625 -4375);
DISPLAY INVISIBLE (-2625 -4375);
FORCEADD UNIVERSAL_POWER..1
(-1550 -4375);
FORCEPROP 3 LASTPIN (-1550 -4425) SIG_NAME P12V_SCM_R\g
J 0
(-1540 -4415);
DISPLAY 0.659574 (-1540 -4415);
PAINT MONO (-1540 -4415);
DISPLAY INVISIBLE (-1540 -4415);
FORCEPROP 1 LAST HDL_POWER P12V_SCM_R
J 1
(-1550 -4325);
DISPLAY 0.872340 (-1550 -4325);
PAINT GREEN (-1550 -4325);
FORCEPROP 2 LAST CDS_LIB logical_power
J 0
(-1550 -4375);
DISPLAY INVISIBLE (-1550 -4375);
FORCEPROP 1 LAST PATH I119
J 0
(-1500 -4350);
DISPLAY 0.872340 (-1500 -4350);
PAINT AQUA (-1500 -4350);
DISPLAY INVISIBLE (-1500 -4350);
FORCEADD UNIVERSAL_POWER..1
(-1700 -3625);
FORCEPROP 3 LASTPIN (-1700 -3675) SIG_NAME P12V_SCM_R\g
J 0
(-1690 -3665);
DISPLAY 0.659574 (-1690 -3665);
PAINT MONO (-1690 -3665);
DISPLAY INVISIBLE (-1690 -3665);
FORCEPROP 1 LAST HDL_POWER P12V_SCM_R
J 1
(-1700 -3575);
DISPLAY 0.872340 (-1700 -3575);
PAINT GREEN (-1700 -3575);
FORCEPROP 1 LAST PATH I120
J 0
(-1650 -3600);
DISPLAY 0.872340 (-1650 -3600);
PAINT AQUA (-1650 -3600);
DISPLAY INVISIBLE (-1650 -3600);
FORCEPROP 2 LAST CDS_LIB logical_power
J 0
(-1700 -3625);
DISPLAY INVISIBLE (-1700 -3625);
FORCEADD UNIVERSAL_POWER..1
(2575 -3225);
FORCEPROP 3 LASTPIN (2575 -3275) SIG_NAME P3V3_AUX\g
J 0
(2585 -3265);
DISPLAY 0.659574 (2585 -3265);
PAINT MONO (2585 -3265);
DISPLAY INVISIBLE (2585 -3265);
FORCEPROP 1 LAST HDL_POWER P3V3_AUX
J 1
(2575 -3175);
DISPLAY 0.872340 (2575 -3175);
PAINT GREEN (2575 -3175);
FORCEPROP 2 LAST CDS_LIB logical_power
J 0
(2575 -3225);
DISPLAY INVISIBLE (2575 -3225);
FORCEPROP 1 LAST PATH I121
J 0
(2625 -3200);
DISPLAY 0.872340 (2625 -3200);
PAINT AQUA (2625 -3200);
DISPLAY INVISIBLE (2625 -3200);
FORCEADD Q_RES..2
(2575 -3425);
FORCEPROP 1 LAST PART_NUMBER CS24702FB06
J 0
(2615 -3550);
DISPLAY 0.787234 (2615 -3550);
DISPLAY INVISIBLE (2615 -3550);
FORCEPROP 1 LAST VALUE 4.7K
J 0
(2620 -3350);
DISPLAY 0.787234 (2620 -3350);
FORCEPROP 1 LAST TOLERANCE 1%
J 0
(2620 -3400);
DISPLAY 0.787234 (2620 -3400);
FORCEPROP 1 LAST MATERIAL CHIP
J 0
(2615 -3500);
DISPLAY 0.787234 (2615 -3500);
FORCEPROP 1 LAST PACK_TYPE 0402LF
J 0
(2615 -3600);
DISPLAY 0.787234 (2615 -3600);
FORCEPROP 1 LAST WATTAGE 1/16W
J 0
(2615 -3450);
DISPLAY 0.787234 (2615 -3450);
FORCEPROP 1 LAST $LOCATION R4091
J 0
(2620 -3300);
DISPLAY 0.978723 (2620 -3300);
FORCEPROP 1 LASTPIN (2575 -3325) $PN 1
J 0
(2580 -3363);
DISPLAY 0.787234 (2580 -3363);
PAINT MONO (2580 -3363);
FORCEPROP 1 LASTPIN (2575 -3525) $PN 2
J 0
(2580 -3515);
DISPLAY 0.787234 (2580 -3515);
PAINT MONO (2580 -3515);
FORCEPROP 2 LAST CDS_LIB pure_quanta
J 0
(2575 -3425);
DISPLAY INVISIBLE (2575 -3425);
FORCEPROP 1 LAST PATH I122
J 0
(2625 -3250);
DISPLAY 0.978723 (2625 -3250);
PAINT WHITE (2625 -3250);
DISPLAY INVISIBLE (2625 -3250);
FORCEPROP 0 LAST CDS_LOCATION R4091
J 0
(2625 -3250);
DISPLAY 1.021277 (2625 -3250);
DISPLAY INVISIBLE (2625 -3250);
FORCEPROP 0 LAST $SEC 1
J 0
(2625 -3250);
DISPLAY 0.680851 (2625 -3250);
PAINT MONO (2625 -3250);
DISPLAY INVISIBLE (2625 -3250);
FORCEPROP 0 LAST CDS_SEC 1
J 0
(2625 -3250);
DISPLAY 1.021277 (2625 -3250);
DISPLAY INVISIBLE (2625 -3250);
FORCEADD UNIVERSAL_POWER..1
(2500 -1075);
FORCEPROP 3 LASTPIN (2500 -1125) SIG_NAME P3V3_AUX\g
J 0
(2510 -1115);
DISPLAY 0.659574 (2510 -1115);
PAINT MONO (2510 -1115);
DISPLAY INVISIBLE (2510 -1115);
FORCEPROP 1 LAST HDL_POWER P3V3_AUX
J 1
(2500 -1025);
DISPLAY 0.872340 (2500 -1025);
PAINT GREEN (2500 -1025);
FORCEPROP 2 LAST CDS_LIB logical_power
J 0
(2500 -1075);
DISPLAY INVISIBLE (2500 -1075);
FORCEPROP 1 LAST PATH I123
J 0
(2550 -1050);
DISPLAY 0.872340 (2550 -1050);
PAINT AQUA (2550 -1050);
DISPLAY INVISIBLE (2550 -1050);
FORCEADD Q_RES..2
(2500 -1275);
FORCEPROP 1 LAST PART_NUMBER CS24702FB06
J 0
(2540 -1400);
DISPLAY 0.787234 (2540 -1400);
DISPLAY INVISIBLE (2540 -1400);
FORCEPROP 1 LAST PACK_TYPE 0402LF
J 0
(2540 -1450);
DISPLAY 0.787234 (2540 -1450);
FORCEPROP 1 LAST VALUE 4.7K
J 0
(2545 -1200);
DISPLAY 0.787234 (2545 -1200);
FORCEPROP 1 LAST TOLERANCE 1%
J 0
(2545 -1250);
DISPLAY 0.787234 (2545 -1250);
FORCEPROP 1 LAST WATTAGE 1/16W
J 0
(2540 -1300);
DISPLAY 0.787234 (2540 -1300);
FORCEPROP 1 LAST MATERIAL CHIP
J 0
(2540 -1350);
DISPLAY 0.787234 (2540 -1350);
FORCEPROP 1 LAST $LOCATION R4090
J 0
(2545 -1150);
DISPLAY 0.978723 (2545 -1150);
FORCEPROP 1 LASTPIN (2500 -1175) $PN 1
J 0
(2505 -1213);
DISPLAY 0.787234 (2505 -1213);
PAINT MONO (2505 -1213);
FORCEPROP 1 LASTPIN (2500 -1375) $PN 2
J 0
(2505 -1365);
DISPLAY 0.787234 (2505 -1365);
PAINT MONO (2505 -1365);
FORCEPROP 2 LAST CDS_LIB pure_quanta
J 0
(2500 -1275);
DISPLAY INVISIBLE (2500 -1275);
FORCEPROP 1 LAST PATH I124
J 0
(2550 -1100);
DISPLAY 0.978723 (2550 -1100);
PAINT WHITE (2550 -1100);
DISPLAY INVISIBLE (2550 -1100);
FORCEPROP 0 LAST CDS_LOCATION R4090
J 0
(2550 -1100);
DISPLAY 1.021277 (2550 -1100);
DISPLAY INVISIBLE (2550 -1100);
FORCEPROP 0 LAST $SEC 1
J 0
(2550 -1100);
DISPLAY 0.680851 (2550 -1100);
PAINT MONO (2550 -1100);
DISPLAY INVISIBLE (2550 -1100);
FORCEPROP 0 LAST CDS_SEC 1
J 0
(2550 -1100);
DISPLAY 1.021277 (2550 -1100);
DISPLAY INVISIBLE (2550 -1100);
FORCEADD UNIVERSAL_POWER..1
(3075 1025);
FORCEPROP 3 LASTPIN (3075 975) SIG_NAME P3V3_AUX\g
J 0
(3085 985);
DISPLAY 0.659574 (3085 985);
PAINT MONO (3085 985);
DISPLAY INVISIBLE (3085 985);
FORCEPROP 1 LAST HDL_POWER P3V3_AUX
J 1
(3075 1075);
DISPLAY 0.872340 (3075 1075);
PAINT GREEN (3075 1075);
FORCEPROP 2 LAST CDS_LIB logical_power
J 0
(3075 1025);
DISPLAY INVISIBLE (3075 1025);
FORCEPROP 1 LAST PATH I125
J 0
(3125 1050);
DISPLAY 0.872340 (3125 1050);
PAINT AQUA (3125 1050);
DISPLAY INVISIBLE (3125 1050);
FORCEADD Q_RES..2
(3075 825);
FORCEPROP 1 LAST PART_NUMBER CS24702FB06
J 0
(3115 700);
DISPLAY 0.787234 (3115 700);
DISPLAY INVISIBLE (3115 700);
FORCEPROP 1 LAST TOLERANCE 1%
J 0
(3120 850);
DISPLAY 0.787234 (3120 850);
FORCEPROP 1 LAST VALUE 4.7K
J 0
(3120 900);
DISPLAY 0.787234 (3120 900);
FORCEPROP 1 LAST PACK_TYPE 0402LF
J 0
(3115 650);
DISPLAY 0.787234 (3115 650);
FORCEPROP 1 LAST WATTAGE 1/16W
J 0
(3115 800);
DISPLAY 0.787234 (3115 800);
FORCEPROP 1 LAST MATERIAL CHIP
J 0
(3115 750);
DISPLAY 0.787234 (3115 750);
FORCEPROP 1 LAST $LOCATION R4092
J 0
(3120 950);
DISPLAY 0.978723 (3120 950);
FORCEPROP 1 LASTPIN (3075 925) $PN 1
J 0
(3080 887);
DISPLAY 0.787234 (3080 887);
PAINT MONO (3080 887);
FORCEPROP 1 LASTPIN (3075 725) $PN 2
J 0
(3080 735);
DISPLAY 0.787234 (3080 735);
PAINT MONO (3080 735);
FORCEPROP 2 LAST CDS_LIB pure_quanta
J 0
(3075 825);
DISPLAY INVISIBLE (3075 825);
FORCEPROP 1 LAST PATH I126
J 0
(3125 1000);
DISPLAY 0.978723 (3125 1000);
PAINT WHITE (3125 1000);
DISPLAY INVISIBLE (3125 1000);
FORCEPROP 0 LAST CDS_LOCATION R4092
J 0
(3125 1000);
DISPLAY 1.021277 (3125 1000);
DISPLAY INVISIBLE (3125 1000);
FORCEPROP 0 LAST $SEC 1
J 0
(3125 1000);
DISPLAY 0.680851 (3125 1000);
PAINT MONO (3125 1000);
DISPLAY INVISIBLE (3125 1000);
FORCEPROP 0 LAST CDS_SEC 1
J 0
(3125 1000);
DISPLAY 1.021277 (3125 1000);
DISPLAY INVISIBLE (3125 1000);
FORCEADD Q_RES..1
(-1750 -275);
FORCEPROP 1 LAST PART_NUMBER CS+0108F128
J 0
(-1900 -200);
DISPLAY 0.638298 (-1900 -200);
DISPLAY INVISIBLE (-1900 -200);
FORCEPROP 1 LAST MATERIAL CHIP
J 0
(-1750 -425);
DISPLAY 0.638298 (-1750 -425);
FORCEPROP 1 LAST TOLERANCE 1%
J 0
(-1750 -375);
DISPLAY 0.638298 (-1750 -375);
FORCEPROP 1 LAST VALUE 0.01
J 2
(-1775 -375);
DISPLAY 0.638298 (-1775 -375);
FORCEPROP 1 LAST WATTAGE 1W
J 2
(-1775 -425);
DISPLAY 0.638298 (-1775 -425);
FORCEPROP 1 LAST PACK_TYPE 2512LF
J 0
(-1650 -375);
DISPLAY 0.638298 (-1650 -375);
FORCEPROP 1 LAST LOCATION R3633
J 0
(-1975 -275);
DISPLAY 0.638298 (-1975 -275);
FORCEPROP 1 LASTPIN (-1850 -275) $PN 1
J 0
(-1838 -263);
DISPLAY 0.787234 (-1838 -263);
PAINT MONO (-1838 -263);
FORCEPROP 1 LASTPIN (-1650 -275) $PN 2
J 0
(-1688 -263);
DISPLAY 0.787234 (-1688 -263);
PAINT MONO (-1688 -263);
FORCEPROP 1 LAST PATH I127
J 0
(-1800 -125);
DISPLAY 0.978723 (-1800 -125);
PAINT WHITE (-1800 -125);
DISPLAY INVISIBLE (-1800 -125);
FORCEPROP 2 LAST CDS_LIB pure_quanta
J 0
(-1750 -275);
DISPLAY INVISIBLE (-1750 -275);
FORCEPROP 0 LAST $SEC 1
J 0
(-1900 -150);
DISPLAY 0.680851 (-1900 -150);
PAINT MONO (-1900 -150);
DISPLAY INVISIBLE (-1900 -150);
FORCEPROP 0 LAST CDS_SEC 1
J 0
(-1900 -150);
DISPLAY 1.021277 (-1900 -150);
DISPLAY INVISIBLE (-1900 -150);
FORCEADD Q_RES..1
(-2150 -2375);
FORCEPROP 1 LAST PART_NUMBER CS+0108F128
J 0
(-2300 -2300);
DISPLAY 0.638298 (-2300 -2300);
DISPLAY INVISIBLE (-2300 -2300);
FORCEPROP 1 LAST WATTAGE 1W
J 2
(-2175 -2525);
DISPLAY 0.638298 (-2175 -2525);
FORCEPROP 1 LAST VALUE 0.01
J 2
(-2175 -2475);
DISPLAY 0.638298 (-2175 -2475);
FORCEPROP 1 LAST TOLERANCE 1%
J 0
(-2150 -2475);
DISPLAY 0.638298 (-2150 -2475);
FORCEPROP 1 LAST MATERIAL CHIP
J 0
(-2150 -2525);
DISPLAY 0.638298 (-2150 -2525);
FORCEPROP 1 LAST PACK_TYPE 2512LF
J 0
(-2050 -2475);
DISPLAY 0.638298 (-2050 -2475);
FORCEPROP 1 LAST LOCATION R3634
J 0
(-2375 -2375);
DISPLAY 0.638298 (-2375 -2375);
FORCEPROP 1 LASTPIN (-2250 -2375) $PN 1
J 0
(-2238 -2363);
DISPLAY 0.787234 (-2238 -2363);
PAINT MONO (-2238 -2363);
FORCEPROP 1 LASTPIN (-2050 -2375) $PN 2
J 0
(-2088 -2363);
DISPLAY 0.787234 (-2088 -2363);
PAINT MONO (-2088 -2363);
FORCEPROP 1 LAST PATH I128
J 0
(-2200 -2225);
DISPLAY 0.978723 (-2200 -2225);
PAINT WHITE (-2200 -2225);
DISPLAY INVISIBLE (-2200 -2225);
FORCEPROP 2 LAST CDS_LIB pure_quanta
J 0
(-2150 -2375);
DISPLAY INVISIBLE (-2150 -2375);
FORCEPROP 0 LAST $SEC 1
J 0
(-2300 -2250);
DISPLAY 0.680851 (-2300 -2250);
PAINT MONO (-2300 -2250);
DISPLAY INVISIBLE (-2300 -2250);
FORCEPROP 0 LAST CDS_SEC 1
J 0
(-2300 -2250);
DISPLAY 1.021277 (-2300 -2250);
DISPLAY INVISIBLE (-2300 -2250);
FORCEADD Q_RES..1
(-2050 -4525);
FORCEPROP 1 LAST PART_NUMBER CS+0108F128
J 0
(-2200 -4450);
DISPLAY 0.638298 (-2200 -4450);
DISPLAY INVISIBLE (-2200 -4450);
FORCEPROP 1 LAST TOLERANCE 1%
J 0
(-2050 -4625);
DISPLAY 0.638298 (-2050 -4625);
FORCEPROP 1 LAST MATERIAL CHIP
J 0
(-2050 -4675);
DISPLAY 0.638298 (-2050 -4675);
FORCEPROP 1 LAST PACK_TYPE 2512LF
J 0
(-1950 -4625);
DISPLAY 0.638298 (-1950 -4625);
FORCEPROP 1 LAST WATTAGE 1W
J 2
(-2075 -4675);
DISPLAY 0.638298 (-2075 -4675);
FORCEPROP 1 LAST VALUE 0.01
J 2
(-2075 -4625);
DISPLAY 0.638298 (-2075 -4625);
FORCEPROP 1 LAST LOCATION R3635
J 0
(-2275 -4525);
DISPLAY 0.638298 (-2275 -4525);
FORCEPROP 1 LASTPIN (-2150 -4525) $PN 1
J 0
(-2138 -4513);
DISPLAY 0.787234 (-2138 -4513);
PAINT MONO (-2138 -4513);
FORCEPROP 1 LASTPIN (-1950 -4525) $PN 2
J 0
(-1988 -4513);
DISPLAY 0.787234 (-1988 -4513);
PAINT MONO (-1988 -4513);
FORCEPROP 1 LAST PATH I129
J 0
(-2100 -4375);
DISPLAY 0.978723 (-2100 -4375);
PAINT WHITE (-2100 -4375);
DISPLAY INVISIBLE (-2100 -4375);
FORCEPROP 2 LAST CDS_LIB pure_quanta
J 0
(-2050 -4525);
DISPLAY INVISIBLE (-2050 -4525);
FORCEPROP 0 LAST $SEC 1
J 0
(-2200 -4400);
DISPLAY 0.680851 (-2200 -4400);
PAINT MONO (-2200 -4400);
DISPLAY INVISIBLE (-2200 -4400);
FORCEPROP 0 LAST CDS_SEC 1
J 0
(-2200 -4400);
DISPLAY 1.021277 (-2200 -4400);
DISPLAY INVISIBLE (-2200 -4400);
FORCEADD UNIVERSAL_POWER..1
(-2750 -2225);
FORCEPROP 3 LASTPIN (-2750 -2275) SIG_NAME P3V3_M2_0\g
J 0
(-2740 -2265);
DISPLAY 0.659574 (-2740 -2265);
PAINT MONO (-2740 -2265);
DISPLAY INVISIBLE (-2740 -2265);
FORCEPROP 1 LAST HDL_POWER P3V3_M2_0
J 1
(-2750 -2175);
DISPLAY 0.872340 (-2750 -2175);
PAINT GREEN (-2750 -2175);
FORCEPROP 2 LAST CDS_LIB logical_power
J 0
(-2750 -2225);
DISPLAY INVISIBLE (-2750 -2225);
FORCEPROP 1 LAST PATH I24
J 0
(-2700 -2200);
DISPLAY 0.872340 (-2700 -2200);
PAINT AQUA (-2700 -2200);
DISPLAY INVISIBLE (-2700 -2200);
FORCEADD Q_CAP..1
(-2075 -1800);
FORCEPROP 1 LAST PART_NUMBER CH4104K1B00
J 0
(-2025 -1950);
DISPLAY 0.808511 (-2025 -1950);
DISPLAY INVISIBLE (-2025 -1950);
FORCEPROP 1 LAST PACK_TYPE 0402
J 0
(-2025 -1950);
DISPLAY 0.638298 (-2025 -1950);
FORCEPROP 1 LAST TOLERANCE 10%
J 0
(-2025 -1850);
DISPLAY 0.638298 (-2025 -1850);
FORCEPROP 1 LAST VOLTAGE 25V
J 0
(-2025 -1800);
DISPLAY 0.638298 (-2025 -1800);
FORCEPROP 1 LAST VALUE 0.1UF
J 0
(-2025 -1750);
DISPLAY 0.638298 (-2025 -1750);
FORCEPROP 1 LAST MATERIAL X7R
J 0
(-2025 -1900);
DISPLAY 0.638298 (-2025 -1900);
FORCEPROP 1 LAST $LOCATION C2018
J 0
(-2025 -1700);
DISPLAY 0.978723 (-2025 -1700);
FORCEPROP 1 LASTPIN (-2075 -1700) $PN 1
J 0
(-2065 -1720);
DISPLAY 0.787234 (-2065 -1720);
PAINT MONO (-2065 -1720);
FORCEPROP 1 LASTPIN (-2075 -1900) $PN 2
J 0
(-2065 -1920);
DISPLAY 0.787234 (-2065 -1920);
PAINT MONO (-2065 -1920);
FORCEPROP 1 LAST PATH I26
J 0
(-2025 -1650);
DISPLAY 0.978723 (-2025 -1650);
PAINT WHITE (-2025 -1650);
DISPLAY INVISIBLE (-2025 -1650);
FORCEPROP 2 LAST CDS_LIB pure_quanta
J 0
(-2075 -1800);
DISPLAY INVISIBLE (-2075 -1800);
FORCEPROP 0 LAST CDS_LOCATION C2018
J 0
(-2025 -1650);
DISPLAY 1.021277 (-2025 -1650);
DISPLAY INVISIBLE (-2025 -1650);
FORCEPROP 0 LAST $SEC 1
J 0
(-2025 -1650);
DISPLAY 0.680851 (-2025 -1650);
PAINT MONO (-2025 -1650);
DISPLAY INVISIBLE (-2025 -1650);
FORCEPROP 0 LAST CDS_SEC 1
J 0
(-2025 -1650);
DISPLAY 1.021277 (-2025 -1650);
DISPLAY INVISIBLE (-2025 -1650);
FORCEADD UNIVERSAL_GND..1
(-2075 -2075);
FORCEPROP 3 LASTPIN (-2075 -2025) SIG_NAME GND\g
J 0
(-2065 -2015);
DISPLAY 0.659574 (-2065 -2015);
PAINT MONO (-2065 -2015);
DISPLAY INVISIBLE (-2065 -2015);
FORCEPROP 1 LAST PATH I27
J 0
(-2000 -2075);
DISPLAY 0.872340 (-2000 -2075);
PAINT AQUA (-2000 -2075);
DISPLAY INVISIBLE (-2000 -2075);
FORCEPROP 1 LAST HDL_POWER GND
J 1
(-2050 -2150);
DISPLAY 0.872340 (-2050 -2150);
PAINT GREEN (-2050 -2150);
DISPLAY INVISIBLE (-2050 -2150);
FORCEPROP 2 LAST CDS_LIB logical_power
J 0
(-2075 -2075);
DISPLAY INVISIBLE (-2075 -2075);
FORCEADD OFFPAGE..3
R 2
(-1500 -2025);
FORCEPROP 2 LAST $XR0 232 
J 0
(-1780 -2025);
DISPLAY 0.638298 (-1780 -2025);
PAINT MONO (-1780 -2025);
FORCEPROP 2 LAST PATH I29
J 0
(-1700 -1975);
DISPLAY 1.021277 (-1700 -1975);
DISPLAY INVISIBLE (-1700 -1975);
FORCEPROP 2 LAST CDS_LIB standard
J 2
(-1500 -2025);
PAINT MONO (-1500 -2025);
DISPLAY INVISIBLE (-1500 -2025);
FORCEPROP 1 LAST COMMENT_BODY TRUE
J 2
(-1450 -2125);
DISPLAY 0.872340 (-1450 -2125);
PAINT GREEN (-1450 -2125);
DISPLAY INVISIBLE (-1450 -2125);
FORCEPROP 1 LAST OFFPAGE TRUE
J 2
(-1825 -2150);
DISPLAY 0.872340 (-1825 -2150);
DISPLAY INVISIBLE (-1825 -2150);
FORCEADD OFFPAGE..1
(-1500 -1975);
FORCEPROP 2 LAST $XR0 232 
J 0
(-1752 -1975);
DISPLAY 0.638298 (-1752 -1975);
PAINT MONO (-1752 -1975);
FORCEPROP 2 LAST PATH I30
J 0
(-1450 -1900);
DISPLAY 1.021277 (-1450 -1900);
DISPLAY INVISIBLE (-1450 -1900);
FORCEPROP 1 LAST COMMENT_BODY TRUE
J 0
(-1375 -2075);
DISPLAY 0.872340 (-1375 -2075);
PAINT GREEN (-1375 -2075);
DISPLAY INVISIBLE (-1375 -2075);
FORCEPROP 1 LAST OFFPAGE TRUE
J 0
(-1175 -2100);
DISPLAY 0.872340 (-1175 -2100);
DISPLAY INVISIBLE (-1175 -2100);
FORCEPROP 2 LAST CDS_LIB standard
J 0
(-1500 -1975);
DISPLAY INVISIBLE (-1500 -1975);
FORCEADD UNIVERSAL_GND..1
(-1475 -1875);
FORCEPROP 3 LASTPIN (-1475 -1825) SIG_NAME GND\g
J 0
(-1465 -1815);
DISPLAY 0.659574 (-1465 -1815);
PAINT MONO (-1465 -1815);
DISPLAY INVISIBLE (-1465 -1815);
FORCEPROP 2 LAST CDS_LIB logical_power
J 0
(-1475 -1875);
DISPLAY INVISIBLE (-1475 -1875);
FORCEPROP 1 LAST HDL_POWER GND
J 1
(-1450 -1950);
DISPLAY 0.872340 (-1450 -1950);
PAINT GREEN (-1450 -1950);
DISPLAY INVISIBLE (-1450 -1950);
FORCEPROP 1 LAST PATH I31
J 0
(-1400 -1875);
DISPLAY 0.872340 (-1400 -1875);
PAINT AQUA (-1400 -1875);
DISPLAY INVISIBLE (-1400 -1875);
FORCEADD UNIVERSAL_POWER..1
(-1825 -1475);
FORCEPROP 3 LASTPIN (-1825 -1525) SIG_NAME P3V3\g
J 0
(-1815 -1515);
DISPLAY 0.659574 (-1815 -1515);
PAINT MONO (-1815 -1515);
DISPLAY INVISIBLE (-1815 -1515);
FORCEPROP 1 LAST HDL_POWER P3V3
J 1
(-1825 -1425);
DISPLAY 0.872340 (-1825 -1425);
PAINT GREEN (-1825 -1425);
FORCEPROP 1 LAST PATH I32
J 0
(-1775 -1450);
DISPLAY 0.872340 (-1775 -1450);
PAINT AQUA (-1775 -1450);
DISPLAY INVISIBLE (-1775 -1450);
FORCEPROP 2 LAST CDS_LIB logical_power
J 0
(-1825 -1475);
DISPLAY INVISIBLE (-1825 -1475);
FORCEADD Q_RES..1
(-275 -2850);
FORCEPROP 1 LAST PART_NUMBER CS01002FB07
J 0
(-425 -2800);
DISPLAY 0.638298 (-425 -2800);
DISPLAY INVISIBLE (-425 -2800);
FORCEPROP 1 LAST PACK_TYPE 0402LF
J 0
(-150 -2900);
DISPLAY 0.638298 (-150 -2900);
FORCEPROP 1 LAST VALUE 10
J 2
(-325 -2900);
DISPLAY 0.638298 (-325 -2900);
FORCEPROP 1 LAST TOLERANCE 1%
J 0
(-225 -2900);
DISPLAY 0.638298 (-225 -2900);
FORCEPROP 1 LAST MATERIAL CHIP
J 0
(-250 -2950);
DISPLAY 0.638298 (-250 -2950);
FORCEPROP 1 LAST WATTAGE 1/16W
J 2
(-275 -2950);
DISPLAY 0.638298 (-275 -2950);
FORCEPROP 1 LAST $LOCATION R3575
J 0
(-525 -2850);
DISPLAY 0.638298 (-525 -2850);
FORCEPROP 1 LASTPIN (-375 -2850) $PN 1
J 0
(-363 -2838);
DISPLAY 0.787234 (-363 -2838);
PAINT MONO (-363 -2838);
FORCEPROP 1 LASTPIN (-175 -2850) $PN 2
J 0
(-213 -2838);
DISPLAY 0.787234 (-213 -2838);
PAINT MONO (-213 -2838);
FORCEPROP 1 LAST PATH I33
J 0
(-325 -2700);
DISPLAY 0.978723 (-325 -2700);
PAINT WHITE (-325 -2700);
DISPLAY INVISIBLE (-325 -2700);
FORCEPROP 2 LAST CDS_LIB pure_quanta
J 0
(-275 -2850);
DISPLAY INVISIBLE (-275 -2850);
FORCEPROP 0 LAST CDS_LOCATION R3575
J 0
(-425 -2750);
DISPLAY 1.021277 (-425 -2750);
DISPLAY INVISIBLE (-425 -2750);
FORCEPROP 0 LAST $SEC 1
J 0
(-425 -2750);
DISPLAY 0.680851 (-425 -2750);
PAINT MONO (-425 -2750);
DISPLAY INVISIBLE (-425 -2750);
FORCEPROP 0 LAST CDS_SEC 1
J 0
(-425 -2750);
DISPLAY 1.021277 (-425 -2750);
DISPLAY INVISIBLE (-425 -2750);
FORCEADD Q_RES..1
(-275 -2575);
FORCEPROP 1 LAST PART_NUMBER CS01002FB07
J 0
(-425 -2525);
DISPLAY 0.638298 (-425 -2525);
DISPLAY INVISIBLE (-425 -2525);
FORCEPROP 1 LAST TOLERANCE 1%
J 0
(-225 -2625);
DISPLAY 0.638298 (-225 -2625);
FORCEPROP 1 LAST WATTAGE 1/16W
J 2
(-275 -2675);
DISPLAY 0.638298 (-275 -2675);
FORCEPROP 1 LAST PACK_TYPE 0402LF
J 0
(-150 -2625);
DISPLAY 0.638298 (-150 -2625);
FORCEPROP 1 LAST VALUE 10
J 2
(-325 -2625);
DISPLAY 0.638298 (-325 -2625);
FORCEPROP 1 LAST MATERIAL CHIP
J 0
(-250 -2675);
DISPLAY 0.638298 (-250 -2675);
FORCEPROP 1 LAST $LOCATION R3574
J 0
(-525 -2575);
DISPLAY 0.638298 (-525 -2575);
FORCEPROP 1 LASTPIN (-375 -2575) $PN 1
J 0
(-363 -2563);
DISPLAY 0.787234 (-363 -2563);
PAINT MONO (-363 -2563);
FORCEPROP 1 LASTPIN (-175 -2575) $PN 2
J 0
(-213 -2563);
DISPLAY 0.787234 (-213 -2563);
PAINT MONO (-213 -2563);
FORCEPROP 1 LAST PATH I35
J 0
(-325 -2425);
DISPLAY 0.978723 (-325 -2425);
PAINT WHITE (-325 -2425);
DISPLAY INVISIBLE (-325 -2425);
FORCEPROP 2 LAST CDS_LIB pure_quanta
J 0
(-275 -2575);
DISPLAY INVISIBLE (-275 -2575);
FORCEPROP 0 LAST CDS_LOCATION R3574
J 0
(-425 -2475);
DISPLAY 1.021277 (-425 -2475);
DISPLAY INVISIBLE (-425 -2475);
FORCEPROP 0 LAST $SEC 1
J 0
(-425 -2475);
DISPLAY 0.680851 (-425 -2475);
PAINT MONO (-425 -2475);
DISPLAY INVISIBLE (-425 -2475);
FORCEPROP 0 LAST CDS_SEC 1
J 0
(-425 -2475);
DISPLAY 1.021277 (-425 -2475);
DISPLAY INVISIBLE (-425 -2475);
FORCEADD Q_RES..1
(-1050 -1750);
FORCEPROP 1 LAST PART_NUMBER CS24702FB06
J 0
(-1475 -1750);
DISPLAY 0.510638 (-1475 -1750);
DISPLAY INVISIBLE (-1475 -1750);
FORCEPROP 1 LAST WATTAGE 1/16W
J 2
(-725 -1750);
DISPLAY 0.510638 (-725 -1750);
FORCEPROP 1 LAST VALUE 4.7K
J 2
(-850 -1750);
DISPLAY 0.510638 (-850 -1750);
FORCEPROP 1 LAST TOLERANCE 1%
J 0
(-725 -1750);
DISPLAY 0.510638 (-725 -1750);
FORCEPROP 1 LAST MATERIAL CHIP
J 0
(-675 -1750);
DISPLAY 0.510638 (-675 -1750);
FORCEPROP 1 LAST PACK_TYPE 0402LF
J 0
(-575 -1750);
DISPLAY 0.510638 (-575 -1750);
FORCEPROP 1 LAST $LOCATION R3611
J 0
(-1175 -1750);
DISPLAY 0.638298 (-1175 -1750);
FORCEPROP 1 LASTPIN (-1150 -1750) $PN 1
J 0
(-1138 -1738);
DISPLAY 0.787234 (-1138 -1738);
PAINT MONO (-1138 -1738);
FORCEPROP 1 LASTPIN (-950 -1750) $PN 2
J 0
(-988 -1738);
DISPLAY 0.787234 (-988 -1738);
PAINT MONO (-988 -1738);
FORCEPROP 2 LAST CDS_LIB pure_quanta
J 0
(-1050 -1750);
DISPLAY INVISIBLE (-1050 -1750);
FORCEPROP 1 LAST PATH I36
J 0
(-1100 -1600);
DISPLAY 0.978723 (-1100 -1600);
PAINT WHITE (-1100 -1600);
DISPLAY INVISIBLE (-1100 -1600);
FORCEPROP 0 LAST CDS_LOCATION R3611
J 0
(-1175 -1700);
DISPLAY 1.021277 (-1175 -1700);
DISPLAY INVISIBLE (-1175 -1700);
FORCEPROP 0 LAST $SEC 1
J 0
(-1175 -1700);
DISPLAY 0.680851 (-1175 -1700);
PAINT MONO (-1175 -1700);
DISPLAY INVISIBLE (-1175 -1700);
FORCEPROP 0 LAST CDS_SEC 1
J 0
(-1175 -1700);
DISPLAY 1.021277 (-1175 -1700);
DISPLAY INVISIBLE (-1175 -1700);
FORCEADD Q_RES..1
(-300 -2025);
FORCEPROP 1 LAST PART_NUMBER CS03322FB03
J 0
(-425 -1975);
DISPLAY 0.638298 (-425 -1975);
DISPLAY INVISIBLE (-425 -1975);
FORCEPROP 1 LAST MATERIAL CHIP
J 0
(0 -2025);
DISPLAY 0.510638 (0 -2025);
FORCEPROP 1 LAST TOLERANCE 1%
J 0
(-75 -2025);
DISPLAY 0.510638 (-75 -2025);
FORCEPROP 1 LAST VALUE 33.2
J 2
(-100 -2025);
DISPLAY 0.510638 (-100 -2025);
FORCEPROP 1 LAST $LOCATION R3573
J 0
(-550 -2025);
DISPLAY 0.787234 (-550 -2025);
FORCEPROP 1 LASTPIN (-400 -2025) $PN 1
J 0
(-388 -2013);
DISPLAY 0.787234 (-388 -2013);
FORCEPROP 1 LASTPIN (-200 -2025) $PN 2
J 0
(-238 -2013);
DISPLAY 0.787234 (-238 -2013);
FORCEPROP 1 LAST PATH I37
J 0
(-350 -1875);
DISPLAY 0.978723 (-350 -1875);
PAINT WHITE (-350 -1875);
DISPLAY INVISIBLE (-350 -1875);
FORCEPROP 1 LAST WATTAGE 1/16W
J 2
(-100 -1925);
DISPLAY 0.638298 (-100 -1925);
DISPLAY INVISIBLE (-100 -1925);
FORCEPROP 1 LAST PACK_TYPE 0402LF
J 0
(50 -2025);
DISPLAY 0.638298 (50 -2025);
DISPLAY INVISIBLE (50 -2025);
FORCEPROP 2 LAST CDS_LIB pure_quanta
J 0
(-300 -2025);
PAINT MONO (-300 -2025);
DISPLAY INVISIBLE (-300 -2025);
FORCEPROP 2 LAST CDS_LOCATION R3573
J 0
(-350 -1825);
DISPLAY 1.021277 (-350 -1825);
DISPLAY INVISIBLE (-350 -1825);
FORCEPROP 2 LAST $SEC 1
J 0
(-350 -1825);
DISPLAY 0.680851 (-350 -1825);
PAINT MONO (-350 -1825);
DISPLAY INVISIBLE (-350 -1825);
FORCEPROP 2 LAST CDS_SEC 1
J 0
(-350 -1825);
DISPLAY 1.021277 (-350 -1825);
DISPLAY INVISIBLE (-350 -1825);
FORCEADD Q_RES..1
(-300 -1975);
FORCEPROP 1 LAST PART_NUMBER CS03322FB03
J 0
(-450 -1925);
DISPLAY 0.510638 (-450 -1925);
DISPLAY INVISIBLE (-450 -1925);
FORCEPROP 1 LAST WATTAGE 1/16W
J 2
(-175 -1900);
DISPLAY 0.510638 (-175 -1900);
FORCEPROP 1 LAST MATERIAL CHIP
J 0
(0 -1975);
DISPLAY 0.510638 (0 -1975);
FORCEPROP 1 LAST TOLERANCE 1%
J 0
(-75 -1975);
DISPLAY 0.510638 (-75 -1975);
FORCEPROP 1 LAST PACK_TYPE 0402LF
J 0
(-450 -1900);
DISPLAY 0.510638 (-450 -1900);
FORCEPROP 1 LAST VALUE 33.2
J 2
(-100 -1975);
DISPLAY 0.510638 (-100 -1975);
FORCEPROP 1 LAST $LOCATION R3572
J 0
(-550 -1975);
DISPLAY 0.787234 (-550 -1975);
FORCEPROP 1 LASTPIN (-400 -1975) $PN 1
J 0
(-388 -1963);
DISPLAY 0.787234 (-388 -1963);
FORCEPROP 1 LASTPIN (-200 -1975) $PN 2
J 0
(-238 -1963);
DISPLAY 0.787234 (-238 -1963);
FORCEPROP 1 LAST PATH I38
J 0
(-350 -1825);
DISPLAY 0.978723 (-350 -1825);
PAINT WHITE (-350 -1825);
DISPLAY INVISIBLE (-350 -1825);
FORCEPROP 2 LAST CDS_LIB pure_quanta
J 0
(-300 -1975);
PAINT MONO (-300 -1975);
DISPLAY INVISIBLE (-300 -1975);
FORCEPROP 2 LAST CDS_LOCATION R3572
J 0
(-350 -1775);
DISPLAY 1.021277 (-350 -1775);
DISPLAY INVISIBLE (-350 -1775);
FORCEPROP 2 LAST $SEC 1
J 0
(-350 -1775);
DISPLAY 0.680851 (-350 -1775);
PAINT MONO (-350 -1775);
DISPLAY INVISIBLE (-350 -1775);
FORCEPROP 2 LAST CDS_SEC 1
J 0
(-350 -1775);
DISPLAY 1.021277 (-350 -1775);
DISPLAY INVISIBLE (-350 -1775);
FORCEADD UNIVERSAL_GND..1
(600 -1650);
FORCEPROP 3 LASTPIN (600 -1600) SIG_NAME GND\g
J 0
(610 -1590);
DISPLAY 0.659574 (610 -1590);
PAINT MONO (610 -1590);
DISPLAY INVISIBLE (610 -1590);
FORCEPROP 1 LAST PATH I39
J 0
(675 -1650);
DISPLAY 0.872340 (675 -1650);
PAINT AQUA (675 -1650);
DISPLAY INVISIBLE (675 -1650);
FORCEPROP 2 LAST CDS_LIB logical_power
J 0
(600 -1650);
DISPLAY INVISIBLE (600 -1650);
FORCEPROP 1 LAST HDL_POWER GND
J 1
(625 -1725);
DISPLAY 0.872340 (625 -1725);
PAINT GREEN (625 -1725);
DISPLAY INVISIBLE (625 -1725);
FORCEADD UNIVERSAL_GND..1
(1825 -2625);
FORCEPROP 3 LASTPIN (1825 -2575) SIG_NAME GND\g
J 0
(1835 -2565);
DISPLAY 0.659574 (1835 -2565);
PAINT MONO (1835 -2565);
DISPLAY INVISIBLE (1835 -2565);
FORCEPROP 1 LAST PATH I40
J 0
(1900 -2625);
DISPLAY 0.872340 (1900 -2625);
PAINT AQUA (1900 -2625);
DISPLAY INVISIBLE (1900 -2625);
FORCEPROP 1 LAST HDL_POWER GND
J 1
(1850 -2700);
DISPLAY 0.872340 (1850 -2700);
PAINT GREEN (1850 -2700);
DISPLAY INVISIBLE (1850 -2700);
FORCEPROP 2 LAST CDS_LIB logical_power
J 0
(1825 -2625);
DISPLAY INVISIBLE (1825 -2625);
FORCEADD Q_RES..1
(2700 -1725);
FORCEPROP 1 LAST PART_NUMBER CS00002JB13
J 0
(2425 -1850);
DISPLAY 0.723404 (2425 -1850);
PAINT WHITE (2425 -1850);
DISPLAY INVISIBLE (2425 -1850);
FORCEPROP 1 LAST VALUE 0
J 2
(2850 -1725);
DISPLAY 0.574468 (2850 -1725);
FORCEPROP 1 LAST PACK_TYPE 0402LF
J 0
(3000 -1725);
DISPLAY 0.574468 (3000 -1725);
FORCEPROP 1 LAST MATERIAL CHIP
J 0
(2875 -1725);
DISPLAY 0.574468 (2875 -1725);
FORCEPROP 1 LAST $LOCATION R3560
J 0
(2525 -1725);
DISPLAY 0.510638 (2525 -1725);
FORCEPROP 1 LASTPIN (2600 -1725) $PN 1
J 0
(2612 -1713);
DISPLAY 0.787234 (2612 -1713);
PAINT MONO (2612 -1713);
FORCEPROP 1 LASTPIN (2800 -1725) $PN 2
J 0
(2762 -1713);
DISPLAY 0.787234 (2762 -1713);
PAINT MONO (2762 -1713);
FORCEPROP 1 LAST PATH I41
J 0
(2650 -1575);
DISPLAY 0.978723 (2650 -1575);
PAINT WHITE (2650 -1575);
DISPLAY INVISIBLE (2650 -1575);
FORCEPROP 1 LAST WATTAGE 1/16W
J 2
(2775 -1800);
DISPLAY 0.723404 (2775 -1800);
PAINT SKYBLUE (2775 -1800);
DISPLAY INVISIBLE (2775 -1800);
FORCEPROP 1 LAST TOLERANCE 5%
J 0
(2500 -1800);
DISPLAY 0.723404 (2500 -1800);
PAINT SKYBLUE (2500 -1800);
DISPLAY INVISIBLE (2500 -1800);
FORCEPROP 2 LAST CDS_LIB pure_quanta
J 0
(2700 -1725);
DISPLAY INVISIBLE (2700 -1725);
FORCEPROP 0 LAST CDS_LOCATION R3560
J 0
(3000 -1675);
DISPLAY 1.021277 (3000 -1675);
DISPLAY INVISIBLE (3000 -1675);
FORCEPROP 0 LAST $SEC 1
J 0
(3000 -1675);
DISPLAY 0.680851 (3000 -1675);
PAINT MONO (3000 -1675);
DISPLAY INVISIBLE (3000 -1675);
FORCEPROP 0 LAST CDS_SEC 1
J 0
(3000 -1675);
DISPLAY 1.021277 (3000 -1675);
DISPLAY INVISIBLE (3000 -1675);
FORCEADD Q_CAP..1
(600 -1375);
FORCEPROP 1 LAST PART_NUMBER CH4104K1B00
J 0
(650 -1525);
DISPLAY 0.808511 (650 -1525);
DISPLAY INVISIBLE (650 -1525);
FORCEPROP 1 LAST VALUE 0.1UF
J 0
(650 -1325);
DISPLAY 0.638298 (650 -1325);
FORCEPROP 1 LAST PACK_TYPE 0402
J 0
(650 -1525);
DISPLAY 0.638298 (650 -1525);
FORCEPROP 1 LAST TOLERANCE 10%
J 0
(650 -1425);
DISPLAY 0.638298 (650 -1425);
FORCEPROP 1 LAST MATERIAL X7R
J 0
(650 -1475);
DISPLAY 0.638298 (650 -1475);
FORCEPROP 1 LAST VOLTAGE 25V
J 0
(650 -1375);
DISPLAY 0.638298 (650 -1375);
FORCEPROP 1 LAST $LOCATION C2013
J 0
(650 -1275);
DISPLAY 0.978723 (650 -1275);
FORCEPROP 1 LASTPIN (600 -1275) $PN 1
J 0
(610 -1295);
DISPLAY 0.787234 (610 -1295);
PAINT MONO (610 -1295);
FORCEPROP 1 LASTPIN (600 -1475) $PN 2
J 0
(610 -1495);
DISPLAY 0.787234 (610 -1495);
PAINT MONO (610 -1495);
FORCEPROP 1 LAST PATH I42
J 0
(650 -1225);
DISPLAY 0.978723 (650 -1225);
PAINT WHITE (650 -1225);
DISPLAY INVISIBLE (650 -1225);
FORCEPROP 2 LAST CDS_LIB pure_quanta
J 0
(600 -1375);
DISPLAY INVISIBLE (600 -1375);
FORCEPROP 0 LAST CDS_LOCATION C2013
J 0
(650 -1225);
DISPLAY 1.021277 (650 -1225);
DISPLAY INVISIBLE (650 -1225);
FORCEPROP 0 LAST $SEC 1
J 0
(650 -1225);
DISPLAY 0.680851 (650 -1225);
PAINT MONO (650 -1225);
DISPLAY INVISIBLE (650 -1225);
FORCEPROP 0 LAST CDS_SEC 1
J 0
(650 -1225);
DISPLAY 1.021277 (650 -1225);
DISPLAY INVISIBLE (650 -1225);
FORCEADD UNIVERSAL_POWER..1
(850 -975);
FORCEPROP 3 LASTPIN (850 -1025) SIG_NAME P3V3_AUX\g
J 0
(860 -1015);
DISPLAY 0.659574 (860 -1015);
PAINT MONO (860 -1015);
DISPLAY INVISIBLE (860 -1015);
FORCEPROP 1 LAST HDL_POWER P3V3_AUX
J 1
(850 -925);
DISPLAY 0.872340 (850 -925);
PAINT GREEN (850 -925);
FORCEPROP 1 LAST PATH I43
J 0
(900 -950);
DISPLAY 0.872340 (900 -950);
PAINT AQUA (900 -950);
DISPLAY INVISIBLE (900 -950);
FORCEPROP 2 LAST CDS_LIB logical_power
J 0
(850 -975);
DISPLAY INVISIBLE (850 -975);
FORCEADD OFFPAGE..2
(3875 -1725);
FORCEPROP 2 LAST $XR0 214 
J 0
(4064 -1725);
DISPLAY 0.638298 (4064 -1725);
PAINT MONO (4064 -1725);
FORCEPROP 2 LAST PATH I44
J 0
(4050 -1650);
DISPLAY 1.021277 (4050 -1650);
DISPLAY INVISIBLE (4050 -1650);
FORCEPROP 1 LAST OFFPAGE TRUE
J 0
(4200 -1850);
DISPLAY 0.872340 (4200 -1850);
DISPLAY INVISIBLE (4200 -1850);
FORCEPROP 1 LAST COMMENT_BODY TRUE
J 0
(3830 -1820);
DISPLAY 0.872340 (3830 -1820);
PAINT GREEN (3830 -1820);
DISPLAY INVISIBLE (3830 -1820);
FORCEPROP 2 LAST CDS_LIB standard
J 0
(3875 -1725);
DISPLAY INVISIBLE (3875 -1725);
FORCEADD Q_RES..1
(-1050 -1675);
FORCEPROP 1 LAST PART_NUMBER CS24702FB06
J 0
(-1475 -1675);
DISPLAY 0.510638 (-1475 -1675);
DISPLAY INVISIBLE (-1475 -1675);
FORCEPROP 1 LAST WATTAGE 1/16W
J 2
(-725 -1675);
DISPLAY 0.510638 (-725 -1675);
FORCEPROP 1 LAST PACK_TYPE 0402LF
J 0
(-575 -1675);
DISPLAY 0.510638 (-575 -1675);
FORCEPROP 1 LAST MATERIAL EMPTY
J 0
(-675 -1675);
DISPLAY 0.510638 (-675 -1675);
PAINT RED (-675 -1675);
FORCEPROP 1 LAST TOLERANCE 1%
J 0
(-725 -1675);
DISPLAY 0.510638 (-725 -1675);
FORCEPROP 1 LAST VALUE 4.7K
J 2
(-850 -1675);
DISPLAY 0.510638 (-850 -1675);
FORCEPROP 1 LAST $LOCATION R3610
J 0
(-1175 -1675);
DISPLAY 0.638298 (-1175 -1675);
FORCEPROP 1 LASTPIN (-1150 -1675) $PN 1
J 0
(-1138 -1663);
DISPLAY 0.787234 (-1138 -1663);
PAINT MONO (-1138 -1663);
FORCEPROP 1 LASTPIN (-950 -1675) $PN 2
J 0
(-988 -1663);
DISPLAY 0.787234 (-988 -1663);
PAINT MONO (-988 -1663);
FORCEPROP 1 LAST PATH I45
J 0
(-1100 -1525);
DISPLAY 0.978723 (-1100 -1525);
PAINT WHITE (-1100 -1525);
DISPLAY INVISIBLE (-1100 -1525);
FORCEPROP 2 LAST CDS_LIB pure_quanta
J 0
(-1050 -1675);
DISPLAY INVISIBLE (-1050 -1675);
FORCEPROP 0 LAST CDS_LOCATION R3610
J 0
(-1175 -1625);
DISPLAY 1.021277 (-1175 -1625);
DISPLAY INVISIBLE (-1175 -1625);
FORCEPROP 0 LAST $SEC 1
J 0
(-1175 -1625);
DISPLAY 0.680851 (-1175 -1625);
PAINT MONO (-1175 -1625);
DISPLAY INVISIBLE (-1175 -1625);
FORCEPROP 0 LAST CDS_SEC 1
J 0
(-1175 -1625);
DISPLAY 1.021277 (-1175 -1625);
DISPLAY INVISIBLE (-1175 -1625);
FORCEADD INA230AIRGTR..1
(1300 -1975);
FORCEPROP 1 LAST PART_NUMBER AL000230001
J 0
(1053 -1539);
DISPLAY 0.723404 (1053 -1539);
PAINT GREEN (1053 -1539);
DISPLAY INVISIBLE (1053 -1539);
FORCEPROP 2 LAST VALUE INA230AIRGTR
J 0
(1025 -1350);
DISPLAY 1.021277 (1025 -1350);
FORCEPROP 1 LAST MATERIAL IC
J 0
(1053 -1666);
DISPLAY 0.723404 (1053 -1666);
PAINT GREEN (1053 -1666);
FORCEPROP 2 LAST PART_TYPE SMLF
J 0
(1025 -1300);
DISPLAY 1.021277 (1025 -1300);
FORCEPROP 1 LAST $LOCATION U264
J 0
(1053 -1392);
DISPLAY 0.723404 (1053 -1392);
PAINT GREEN (1053 -1392);
FORCEPROP 0 LASTPIN (900 -1875) $PN 2
J 2
(890 -1865);
DISPLAY 0.680851 (890 -1865);
PAINT MONO (890 -1865);
FORCEPROP 0 LASTPIN (900 -1825) $PN 1
J 2
(890 -1815);
DISPLAY 0.680851 (890 -1815);
PAINT MONO (890 -1815);
FORCEPROP 0 LASTPIN (1700 -1725) $PN 3
J 0
(1710 -1715);
DISPLAY 0.680851 (1710 -1715);
PAINT MONO (1710 -1715);
FORCEPROP 0 LASTPIN (900 -2125) $PN 11
J 2
(890 -2115);
DISPLAY 0.680851 (890 -2115);
PAINT MONO (890 -2115);
FORCEPROP 0 LASTPIN (1700 -2175) $PN 10
J 0
(1710 -2165);
DISPLAY 0.680851 (1710 -2165);
PAINT MONO (1710 -2165);
FORCEPROP 0 LASTPIN (900 -2175) $PN 13
J 2
(890 -2165);
DISPLAY 0.680851 (890 -2165);
PAINT MONO (890 -2165);
FORCEPROP 0 LASTPIN (900 -2225) $PN 12
J 2
(890 -2215);
DISPLAY 0.680851 (890 -2215);
PAINT MONO (890 -2215);
FORCEPROP 0 LASTPIN (1700 -1825) $PN 6
J 0
(1710 -1815);
DISPLAY 0.680851 (1710 -1815);
PAINT MONO (1710 -1815);
FORCEPROP 0 LASTPIN (1700 -1875) $PN 7
J 0
(1710 -1865);
DISPLAY 0.680851 (1710 -1865);
PAINT MONO (1710 -1865);
FORCEPROP 0 LASTPIN (1700 -1925) $PN 8
J 0
(1710 -1915);
DISPLAY 0.680851 (1710 -1915);
PAINT MONO (1710 -1915);
FORCEPROP 0 LASTPIN (1700 -1975) $PN 14
J 0
(1710 -1965);
DISPLAY 0.680851 (1710 -1965);
PAINT MONO (1710 -1965);
FORCEPROP 0 LASTPIN (1700 -2025) $PN 15
J 0
(1710 -2015);
DISPLAY 0.680851 (1710 -2015);
PAINT MONO (1710 -2015);
FORCEPROP 0 LASTPIN (1700 -2075) $PN 16
J 0
(1710 -2065);
DISPLAY 0.680851 (1710 -2065);
PAINT MONO (1710 -2065);
FORCEPROP 0 LASTPIN (900 -1975) $PN 5
J 2
(890 -1965);
DISPLAY 0.680851 (890 -1965);
PAINT MONO (890 -1965);
FORCEPROP 0 LASTPIN (900 -2025) $PN 4
J 2
(890 -2015);
DISPLAY 0.680851 (890 -2015);
PAINT MONO (890 -2015);
FORCEPROP 0 LASTPIN (1700 -2225) $PN TH
J 0
(1710 -2215);
DISPLAY 0.680851 (1710 -2215);
PAINT MONO (1710 -2215);
FORCEPROP 0 LASTPIN (900 -1725) $PN 9
J 2
(890 -1715);
DISPLAY 0.680851 (890 -1715);
PAINT MONO (890 -1715);
FORCEPROP 1 LAST NEEDS_NO_SIZE TRUE
J 0
(1300 -1975);
DISPLAY 0.723404 (1300 -1975);
PAINT GREEN (1300 -1975);
DISPLAY INVISIBLE (1300 -1975);
FORCEPROP 1 LAST PATH I46
J 0
(1300 -1975);
DISPLAY 0.723404 (1300 -1975);
PAINT GREEN (1300 -1975);
DISPLAY INVISIBLE (1300 -1975);
FORCEPROP 1 LAST CDS_LMAN_SYM_OUTLINE -250,300,250,-300
J 0
(1300 -1975);
DISPLAY 0.468085 (1300 -1975);
PAINT GREEN (1300 -1975);
DISPLAY INVISIBLE (1300 -1975);
FORCEPROP 2 LAST CDS_LIB pure_quanta
J 0
(1300 -1975);
DISPLAY INVISIBLE (1300 -1975);
FORCEPROP 0 LAST CDS_LOCATION U264
J 0
(1025 -1250);
DISPLAY 1.021277 (1025 -1250);
DISPLAY INVISIBLE (1025 -1250);
FORCEPROP 0 LAST $SEC 1
J 0
(1025 -1250);
DISPLAY 0.680851 (1025 -1250);
PAINT MONO (1025 -1250);
DISPLAY INVISIBLE (1025 -1250);
FORCEPROP 0 LAST CDS_SEC 1
J 0
(1025 -1250);
DISPLAY 1.021277 (1025 -1250);
DISPLAY INVISIBLE (1025 -1250);
FORCEADD Q_CAP..1
(-1950 -3950);
FORCEPROP 1 LAST PART_NUMBER CH4104K1B00
J 0
(-1900 -4100);
DISPLAY 0.808511 (-1900 -4100);
DISPLAY INVISIBLE (-1900 -4100);
FORCEPROP 1 LAST VOLTAGE 25V
J 0
(-1900 -3950);
DISPLAY 0.638298 (-1900 -3950);
FORCEPROP 1 LAST MATERIAL X7R
J 0
(-1900 -4050);
DISPLAY 0.638298 (-1900 -4050);
FORCEPROP 1 LAST VALUE 0.1UF
J 0
(-1900 -3900);
DISPLAY 0.638298 (-1900 -3900);
FORCEPROP 1 LAST PACK_TYPE 0402
J 0
(-1900 -4100);
DISPLAY 0.638298 (-1900 -4100);
FORCEPROP 1 LAST TOLERANCE 10%
J 0
(-1900 -4000);
DISPLAY 0.638298 (-1900 -4000);
FORCEPROP 1 LAST $LOCATION C2019
J 0
(-1900 -3850);
DISPLAY 0.978723 (-1900 -3850);
FORCEPROP 1 LASTPIN (-1950 -3850) $PN 1
J 0
(-1940 -3870);
DISPLAY 0.787234 (-1940 -3870);
PAINT MONO (-1940 -3870);
FORCEPROP 1 LASTPIN (-1950 -4050) $PN 2
J 0
(-1940 -4070);
DISPLAY 0.787234 (-1940 -4070);
PAINT MONO (-1940 -4070);
FORCEPROP 2 LAST CDS_LIB pure_quanta
J 0
(-1950 -3950);
DISPLAY INVISIBLE (-1950 -3950);
FORCEPROP 1 LAST PATH I49
J 0
(-1900 -3800);
DISPLAY 0.978723 (-1900 -3800);
PAINT WHITE (-1900 -3800);
DISPLAY INVISIBLE (-1900 -3800);
FORCEPROP 0 LAST CDS_LOCATION C2019
J 0
(-1900 -3800);
DISPLAY 1.021277 (-1900 -3800);
DISPLAY INVISIBLE (-1900 -3800);
FORCEPROP 0 LAST $SEC 1
J 0
(-1900 -3800);
DISPLAY 0.680851 (-1900 -3800);
PAINT MONO (-1900 -3800);
DISPLAY INVISIBLE (-1900 -3800);
FORCEPROP 0 LAST CDS_SEC 1
J 0
(-1900 -3800);
DISPLAY 1.021277 (-1900 -3800);
DISPLAY INVISIBLE (-1900 -3800);
FORCEADD UNIVERSAL_GND..1
(-1950 -4225);
FORCEPROP 3 LASTPIN (-1950 -4175) SIG_NAME GND\g
J 0
(-1940 -4165);
DISPLAY 0.659574 (-1940 -4165);
PAINT MONO (-1940 -4165);
DISPLAY INVISIBLE (-1940 -4165);
FORCEPROP 2 LAST CDS_LIB logical_power
J 0
(-1950 -4225);
DISPLAY INVISIBLE (-1950 -4225);
FORCEPROP 1 LAST HDL_POWER GND
J 1
(-1925 -4300);
DISPLAY 0.872340 (-1925 -4300);
PAINT GREEN (-1925 -4300);
DISPLAY INVISIBLE (-1925 -4300);
FORCEPROP 1 LAST PATH I50
J 0
(-1875 -4225);
DISPLAY 0.872340 (-1875 -4225);
PAINT AQUA (-1875 -4225);
DISPLAY INVISIBLE (-1875 -4225);
FORCEADD OFFPAGE..3
R 2
(-1375 -4175);
FORCEPROP 2 LAST $XR0 232 
J 0
(-1655 -4175);
DISPLAY 0.638298 (-1655 -4175);
PAINT MONO (-1655 -4175);
FORCEPROP 1 LAST OFFPAGE TRUE
J 2
(-1700 -4300);
DISPLAY 0.872340 (-1700 -4300);
DISPLAY INVISIBLE (-1700 -4300);
FORCEPROP 1 LAST COMMENT_BODY TRUE
J 2
(-1325 -4275);
DISPLAY 0.872340 (-1325 -4275);
PAINT GREEN (-1325 -4275);
DISPLAY INVISIBLE (-1325 -4275);
FORCEPROP 2 LAST CDS_LIB standard
J 2
(-1375 -4175);
PAINT MONO (-1375 -4175);
DISPLAY INVISIBLE (-1375 -4175);
FORCEPROP 2 LAST PATH I52
J 0
(-1575 -4125);
DISPLAY 1.021277 (-1575 -4125);
DISPLAY INVISIBLE (-1575 -4125);
FORCEADD OFFPAGE..1
(-1375 -4125);
FORCEPROP 2 LAST $XR0 232 
J 0
(-1627 -4125);
DISPLAY 0.638298 (-1627 -4125);
PAINT MONO (-1627 -4125);
FORCEPROP 2 LAST CDS_LIB standard
J 0
(-1375 -4125);
DISPLAY INVISIBLE (-1375 -4125);
FORCEPROP 1 LAST OFFPAGE TRUE
J 0
(-1050 -4250);
DISPLAY 0.872340 (-1050 -4250);
DISPLAY INVISIBLE (-1050 -4250);
FORCEPROP 1 LAST COMMENT_BODY TRUE
J 0
(-1250 -4225);
DISPLAY 0.872340 (-1250 -4225);
PAINT GREEN (-1250 -4225);
DISPLAY INVISIBLE (-1250 -4225);
FORCEPROP 2 LAST PATH I53
J 0
(-1325 -4050);
DISPLAY 1.021277 (-1325 -4050);
DISPLAY INVISIBLE (-1325 -4050);
FORCEADD UNIVERSAL_GND..1
(-1400 -4050);
FORCEPROP 3 LASTPIN (-1400 -4000) SIG_NAME GND\g
J 0
(-1390 -3990);
DISPLAY 0.659574 (-1390 -3990);
PAINT MONO (-1390 -3990);
DISPLAY INVISIBLE (-1390 -3990);
FORCEPROP 2 LAST CDS_LIB logical_power
J 0
(-1400 -4050);
DISPLAY INVISIBLE (-1400 -4050);
FORCEPROP 1 LAST HDL_POWER GND
J 1
(-1375 -4125);
DISPLAY 0.872340 (-1375 -4125);
PAINT GREEN (-1375 -4125);
DISPLAY INVISIBLE (-1375 -4125);
FORCEPROP 1 LAST PATH I54
J 0
(-1325 -4050);
DISPLAY 0.872340 (-1325 -4050);
PAINT AQUA (-1325 -4050);
DISPLAY INVISIBLE (-1325 -4050);
FORCEADD Q_RES..1
(-150 -5000);
FORCEPROP 1 LAST PART_NUMBER CS01002FB07
J 0
(-300 -4950);
DISPLAY 0.638298 (-300 -4950);
DISPLAY INVISIBLE (-300 -4950);
FORCEPROP 1 LAST MATERIAL CHIP
J 0
(-125 -5100);
DISPLAY 0.638298 (-125 -5100);
FORCEPROP 1 LAST PACK_TYPE 0402LF
J 0
(-25 -5050);
DISPLAY 0.638298 (-25 -5050);
FORCEPROP 1 LAST VALUE 10
J 2
(-200 -5050);
DISPLAY 0.638298 (-200 -5050);
FORCEPROP 1 LAST TOLERANCE 1%
J 0
(-100 -5050);
DISPLAY 0.638298 (-100 -5050);
FORCEPROP 1 LAST WATTAGE 1/16W
J 2
(-150 -5100);
DISPLAY 0.638298 (-150 -5100);
FORCEPROP 1 LAST $LOCATION R3579
J 0
(-400 -5000);
DISPLAY 0.638298 (-400 -5000);
FORCEPROP 1 LASTPIN (-250 -5000) $PN 1
J 0
(-238 -4988);
DISPLAY 0.787234 (-238 -4988);
PAINT MONO (-238 -4988);
FORCEPROP 1 LASTPIN (-50 -5000) $PN 2
J 0
(-88 -4988);
DISPLAY 0.787234 (-88 -4988);
PAINT MONO (-88 -4988);
FORCEPROP 2 LAST CDS_LIB pure_quanta
J 0
(-150 -5000);
DISPLAY INVISIBLE (-150 -5000);
FORCEPROP 1 LAST PATH I56
J 0
(-200 -4850);
DISPLAY 0.978723 (-200 -4850);
PAINT WHITE (-200 -4850);
DISPLAY INVISIBLE (-200 -4850);
FORCEPROP 0 LAST CDS_LOCATION R3579
J 0
(-300 -4900);
DISPLAY 1.021277 (-300 -4900);
DISPLAY INVISIBLE (-300 -4900);
FORCEPROP 0 LAST $SEC 1
J 0
(-300 -4900);
DISPLAY 0.680851 (-300 -4900);
PAINT MONO (-300 -4900);
DISPLAY INVISIBLE (-300 -4900);
FORCEPROP 0 LAST CDS_SEC 1
J 0
(-300 -4900);
DISPLAY 1.021277 (-300 -4900);
DISPLAY INVISIBLE (-300 -4900);
FORCEADD Q_RES..1
(-150 -4725);
FORCEPROP 1 LAST PART_NUMBER CS01002FB07
J 0
(-300 -4675);
DISPLAY 0.638298 (-300 -4675);
DISPLAY INVISIBLE (-300 -4675);
FORCEPROP 1 LAST PACK_TYPE 0402LF
J 0
(-25 -4775);
DISPLAY 0.638298 (-25 -4775);
FORCEPROP 1 LAST VALUE 10
J 2
(-200 -4775);
DISPLAY 0.638298 (-200 -4775);
FORCEPROP 1 LAST TOLERANCE 1%
J 0
(-100 -4775);
DISPLAY 0.638298 (-100 -4775);
FORCEPROP 1 LAST MATERIAL CHIP
J 0
(-125 -4825);
DISPLAY 0.638298 (-125 -4825);
FORCEPROP 1 LAST WATTAGE 1/16W
J 2
(-150 -4825);
DISPLAY 0.638298 (-150 -4825);
FORCEPROP 1 LAST $LOCATION R3578
J 0
(-400 -4725);
DISPLAY 0.638298 (-400 -4725);
FORCEPROP 1 LASTPIN (-250 -4725) $PN 1
J 0
(-238 -4713);
DISPLAY 0.787234 (-238 -4713);
PAINT MONO (-238 -4713);
FORCEPROP 1 LASTPIN (-50 -4725) $PN 2
J 0
(-88 -4713);
DISPLAY 0.787234 (-88 -4713);
PAINT MONO (-88 -4713);
FORCEPROP 2 LAST CDS_LIB pure_quanta
J 0
(-150 -4725);
DISPLAY INVISIBLE (-150 -4725);
FORCEPROP 1 LAST PATH I58
J 0
(-200 -4575);
DISPLAY 0.978723 (-200 -4575);
PAINT WHITE (-200 -4575);
DISPLAY INVISIBLE (-200 -4575);
FORCEPROP 0 LAST CDS_LOCATION R3578
J 0
(-300 -4625);
DISPLAY 1.021277 (-300 -4625);
DISPLAY INVISIBLE (-300 -4625);
FORCEPROP 0 LAST $SEC 1
J 0
(-300 -4625);
DISPLAY 0.680851 (-300 -4625);
PAINT MONO (-300 -4625);
DISPLAY INVISIBLE (-300 -4625);
FORCEPROP 0 LAST CDS_SEC 1
J 0
(-300 -4625);
DISPLAY 1.021277 (-300 -4625);
DISPLAY INVISIBLE (-300 -4625);
FORCEADD Q_RES..1
(-975 -3925);
FORCEPROP 1 LAST PART_NUMBER CS24702FB06
J 0
(-1400 -3925);
DISPLAY 0.510638 (-1400 -3925);
DISPLAY INVISIBLE (-1400 -3925);
FORCEPROP 1 LAST VALUE 4.7K
J 2
(-775 -3925);
DISPLAY 0.510638 (-775 -3925);
FORCEPROP 1 LAST TOLERANCE 1%
J 0
(-650 -3925);
DISPLAY 0.510638 (-650 -3925);
FORCEPROP 1 LAST WATTAGE 1/16W
J 2
(-650 -3925);
DISPLAY 0.510638 (-650 -3925);
FORCEPROP 1 LAST PACK_TYPE 0402LF
J 0
(-500 -3925);
DISPLAY 0.510638 (-500 -3925);
FORCEPROP 1 LAST MATERIAL EMPTY
J 0
(-600 -3925);
DISPLAY 0.510638 (-600 -3925);
PAINT RED (-600 -3925);
FORCEPROP 1 LAST $LOCATION R3613
J 0
(-1100 -3925);
DISPLAY 0.638298 (-1100 -3925);
FORCEPROP 1 LASTPIN (-1075 -3925) $PN 1
J 0
(-1063 -3913);
DISPLAY 0.787234 (-1063 -3913);
PAINT MONO (-1063 -3913);
FORCEPROP 1 LASTPIN (-875 -3925) $PN 2
J 0
(-913 -3913);
DISPLAY 0.787234 (-913 -3913);
PAINT MONO (-913 -3913);
FORCEPROP 1 LAST PATH I59
J 0
(-1025 -3775);
DISPLAY 0.978723 (-1025 -3775);
PAINT WHITE (-1025 -3775);
DISPLAY INVISIBLE (-1025 -3775);
FORCEPROP 2 LAST CDS_LIB pure_quanta
J 0
(-975 -3925);
DISPLAY INVISIBLE (-975 -3925);
FORCEPROP 0 LAST CDS_LOCATION R3613
J 0
(-1100 -3875);
DISPLAY 1.021277 (-1100 -3875);
DISPLAY INVISIBLE (-1100 -3875);
FORCEPROP 0 LAST $SEC 1
J 0
(-1100 -3875);
DISPLAY 0.680851 (-1100 -3875);
PAINT MONO (-1100 -3875);
DISPLAY INVISIBLE (-1100 -3875);
FORCEPROP 0 LAST CDS_SEC 1
J 0
(-1100 -3875);
DISPLAY 1.021277 (-1100 -3875);
DISPLAY INVISIBLE (-1100 -3875);
FORCEADD Q_RES..1
(-175 -4175);
FORCEPROP 1 LAST PART_NUMBER CS03322FB03
J 0
(-300 -4125);
DISPLAY 0.638298 (-300 -4125);
DISPLAY INVISIBLE (-300 -4125);
FORCEPROP 1 LAST MATERIAL CHIP
J 0
(125 -4175);
DISPLAY 0.510638 (125 -4175);
FORCEPROP 1 LAST TOLERANCE 1%
J 0
(50 -4175);
DISPLAY 0.510638 (50 -4175);
FORCEPROP 1 LAST VALUE 33.2
J 2
(25 -4175);
DISPLAY 0.510638 (25 -4175);
FORCEPROP 1 LAST $LOCATION R3577
J 0
(-425 -4175);
DISPLAY 0.787234 (-425 -4175);
FORCEPROP 1 LASTPIN (-275 -4175) $PN 1
J 0
(-263 -4163);
DISPLAY 0.787234 (-263 -4163);
FORCEPROP 1 LASTPIN (-75 -4175) $PN 2
J 0
(-113 -4163);
DISPLAY 0.787234 (-113 -4163);
FORCEPROP 2 LAST CDS_LIB pure_quanta
J 0
(-175 -4175);
PAINT MONO (-175 -4175);
DISPLAY INVISIBLE (-175 -4175);
FORCEPROP 1 LAST PACK_TYPE 0402LF
J 0
(175 -4175);
DISPLAY 0.638298 (175 -4175);
DISPLAY INVISIBLE (175 -4175);
FORCEPROP 1 LAST WATTAGE 1/16W
J 2
(25 -4075);
DISPLAY 0.638298 (25 -4075);
DISPLAY INVISIBLE (25 -4075);
FORCEPROP 1 LAST PATH I60
J 0
(-225 -4025);
DISPLAY 0.978723 (-225 -4025);
PAINT WHITE (-225 -4025);
DISPLAY INVISIBLE (-225 -4025);
FORCEPROP 2 LAST CDS_LOCATION R3577
J 0
(-225 -3975);
DISPLAY 1.021277 (-225 -3975);
DISPLAY INVISIBLE (-225 -3975);
FORCEPROP 2 LAST $SEC 1
J 0
(-225 -3975);
DISPLAY 0.680851 (-225 -3975);
PAINT MONO (-225 -3975);
DISPLAY INVISIBLE (-225 -3975);
FORCEPROP 2 LAST CDS_SEC 1
J 0
(-225 -3975);
DISPLAY 1.021277 (-225 -3975);
DISPLAY INVISIBLE (-225 -3975);
FORCEADD Q_RES..1
(-175 -4125);
FORCEPROP 1 LAST PART_NUMBER CS03322FB03
J 0
(-325 -4075);
DISPLAY 0.510638 (-325 -4075);
DISPLAY INVISIBLE (-325 -4075);
FORCEPROP 1 LAST MATERIAL CHIP
J 0
(125 -4125);
DISPLAY 0.510638 (125 -4125);
FORCEPROP 1 LAST TOLERANCE 1%
J 0
(50 -4125);
DISPLAY 0.510638 (50 -4125);
FORCEPROP 1 LAST WATTAGE 1/16W
J 2
(-50 -4050);
DISPLAY 0.510638 (-50 -4050);
FORCEPROP 1 LAST PACK_TYPE 0402LF
J 0
(-325 -4050);
DISPLAY 0.510638 (-325 -4050);
FORCEPROP 1 LAST VALUE 33.2
J 2
(25 -4125);
DISPLAY 0.510638 (25 -4125);
FORCEPROP 1 LAST $LOCATION R3576
J 0
(-425 -4125);
DISPLAY 0.787234 (-425 -4125);
FORCEPROP 1 LASTPIN (-275 -4125) $PN 1
J 0
(-263 -4113);
DISPLAY 0.787234 (-263 -4113);
FORCEPROP 1 LASTPIN (-75 -4125) $PN 2
J 0
(-113 -4113);
DISPLAY 0.787234 (-113 -4113);
FORCEPROP 2 LAST CDS_LIB pure_quanta
J 0
(-175 -4125);
PAINT MONO (-175 -4125);
DISPLAY INVISIBLE (-175 -4125);
FORCEPROP 1 LAST PATH I61
J 0
(-225 -3975);
DISPLAY 0.978723 (-225 -3975);
PAINT WHITE (-225 -3975);
DISPLAY INVISIBLE (-225 -3975);
FORCEPROP 2 LAST CDS_LOCATION R3576
J 0
(-225 -3925);
DISPLAY 1.021277 (-225 -3925);
DISPLAY INVISIBLE (-225 -3925);
FORCEPROP 2 LAST $SEC 1
J 0
(-225 -3925);
DISPLAY 0.680851 (-225 -3925);
PAINT MONO (-225 -3925);
DISPLAY INVISIBLE (-225 -3925);
FORCEPROP 2 LAST CDS_SEC 1
J 0
(-225 -3925);
DISPLAY 1.021277 (-225 -3925);
DISPLAY INVISIBLE (-225 -3925);
FORCEADD UNIVERSAL_GND..1
(725 -3800);
FORCEPROP 3 LASTPIN (725 -3750) SIG_NAME GND\g
J 0
(735 -3740);
DISPLAY 0.659574 (735 -3740);
PAINT MONO (735 -3740);
DISPLAY INVISIBLE (735 -3740);
FORCEPROP 1 LAST HDL_POWER GND
J 1
(750 -3875);
DISPLAY 0.872340 (750 -3875);
PAINT GREEN (750 -3875);
DISPLAY INVISIBLE (750 -3875);
FORCEPROP 2 LAST CDS_LIB logical_power
J 0
(725 -3800);
DISPLAY INVISIBLE (725 -3800);
FORCEPROP 1 LAST PATH I62
J 0
(800 -3800);
DISPLAY 0.872340 (800 -3800);
PAINT AQUA (800 -3800);
DISPLAY INVISIBLE (800 -3800);
FORCEADD UNIVERSAL_GND..1
(1950 -4775);
FORCEPROP 3 LASTPIN (1950 -4725) SIG_NAME GND\g
J 0
(1960 -4715);
DISPLAY 0.659574 (1960 -4715);
PAINT MONO (1960 -4715);
DISPLAY INVISIBLE (1960 -4715);
FORCEPROP 2 LAST CDS_LIB logical_power
J 0
(1950 -4775);
DISPLAY INVISIBLE (1950 -4775);
FORCEPROP 1 LAST HDL_POWER GND
J 1
(1975 -4850);
DISPLAY 0.872340 (1975 -4850);
PAINT GREEN (1975 -4850);
DISPLAY INVISIBLE (1975 -4850);
FORCEPROP 1 LAST PATH I63
J 0
(2025 -4775);
DISPLAY 0.872340 (2025 -4775);
PAINT AQUA (2025 -4775);
DISPLAY INVISIBLE (2025 -4775);
FORCEADD Q_RES..1
(2825 -3875);
FORCEPROP 1 LAST PART_NUMBER CS00002JB13
J 0
(2550 -4000);
DISPLAY 0.723404 (2550 -4000);
PAINT WHITE (2550 -4000);
DISPLAY INVISIBLE (2550 -4000);
FORCEPROP 1 LAST PACK_TYPE 0402LF
J 0
(3125 -3875);
DISPLAY 0.574468 (3125 -3875);
FORCEPROP 1 LAST VALUE 0
J 2
(2975 -3875);
DISPLAY 0.574468 (2975 -3875);
FORCEPROP 1 LAST MATERIAL CHIP
J 0
(3000 -3875);
DISPLAY 0.574468 (3000 -3875);
FORCEPROP 1 LAST $LOCATION R3561
J 0
(2650 -3875);
DISPLAY 0.510638 (2650 -3875);
FORCEPROP 1 LASTPIN (2725 -3875) $PN 1
J 0
(2737 -3863);
DISPLAY 0.787234 (2737 -3863);
PAINT MONO (2737 -3863);
FORCEPROP 1 LASTPIN (2925 -3875) $PN 2
J 0
(2887 -3863);
DISPLAY 0.787234 (2887 -3863);
PAINT MONO (2887 -3863);
FORCEPROP 2 LAST CDS_LIB pure_quanta
J 0
(2825 -3875);
DISPLAY INVISIBLE (2825 -3875);
FORCEPROP 1 LAST TOLERANCE 5%
J 0
(2625 -3950);
DISPLAY 0.723404 (2625 -3950);
PAINT SKYBLUE (2625 -3950);
DISPLAY INVISIBLE (2625 -3950);
FORCEPROP 1 LAST WATTAGE 1/16W
J 2
(2900 -3950);
DISPLAY 0.723404 (2900 -3950);
PAINT SKYBLUE (2900 -3950);
DISPLAY INVISIBLE (2900 -3950);
FORCEPROP 1 LAST PATH I64
J 0
(2775 -3725);
DISPLAY 0.978723 (2775 -3725);
PAINT WHITE (2775 -3725);
DISPLAY INVISIBLE (2775 -3725);
FORCEPROP 0 LAST CDS_LOCATION R3561
J 0
(3125 -3825);
DISPLAY 1.021277 (3125 -3825);
DISPLAY INVISIBLE (3125 -3825);
FORCEPROP 0 LAST $SEC 1
J 0
(3125 -3825);
DISPLAY 0.680851 (3125 -3825);
PAINT MONO (3125 -3825);
DISPLAY INVISIBLE (3125 -3825);
FORCEPROP 0 LAST CDS_SEC 1
J 0
(3125 -3825);
DISPLAY 1.021277 (3125 -3825);
DISPLAY INVISIBLE (3125 -3825);
FORCEADD Q_CAP..1
(725 -3525);
FORCEPROP 1 LAST PART_NUMBER CH4104K1B00
J 0
(775 -3675);
DISPLAY 0.808511 (775 -3675);
DISPLAY INVISIBLE (775 -3675);
FORCEPROP 1 LAST MATERIAL X7R
J 0
(775 -3625);
DISPLAY 0.638298 (775 -3625);
FORCEPROP 1 LAST PACK_TYPE 0402
J 0
(775 -3675);
DISPLAY 0.638298 (775 -3675);
FORCEPROP 1 LAST VALUE 0.1UF
J 0
(775 -3475);
DISPLAY 0.638298 (775 -3475);
FORCEPROP 1 LAST VOLTAGE 25V
J 0
(775 -3525);
DISPLAY 0.638298 (775 -3525);
FORCEPROP 1 LAST TOLERANCE 10%
J 0
(775 -3575);
DISPLAY 0.638298 (775 -3575);
FORCEPROP 1 LAST $LOCATION C2014
J 0
(775 -3425);
DISPLAY 0.978723 (775 -3425);
FORCEPROP 1 LASTPIN (725 -3425) $PN 1
J 0
(735 -3445);
DISPLAY 0.787234 (735 -3445);
PAINT MONO (735 -3445);
FORCEPROP 1 LASTPIN (725 -3625) $PN 2
J 0
(735 -3645);
DISPLAY 0.787234 (735 -3645);
PAINT MONO (735 -3645);
FORCEPROP 2 LAST CDS_LIB pure_quanta
J 0
(725 -3525);
DISPLAY INVISIBLE (725 -3525);
FORCEPROP 1 LAST PATH I65
J 0
(775 -3375);
DISPLAY 0.978723 (775 -3375);
PAINT WHITE (775 -3375);
DISPLAY INVISIBLE (775 -3375);
FORCEPROP 0 LAST CDS_LOCATION C2014
J 0
(775 -3375);
DISPLAY 1.021277 (775 -3375);
DISPLAY INVISIBLE (775 -3375);
FORCEPROP 0 LAST $SEC 1
J 0
(775 -3375);
DISPLAY 0.680851 (775 -3375);
PAINT MONO (775 -3375);
DISPLAY INVISIBLE (775 -3375);
FORCEPROP 0 LAST CDS_SEC 1
J 0
(775 -3375);
DISPLAY 1.021277 (775 -3375);
DISPLAY INVISIBLE (775 -3375);
FORCEADD UNIVERSAL_POWER..1
(975 -3125);
FORCEPROP 3 LASTPIN (975 -3175) SIG_NAME P3V3_AUX\g
J 0
(985 -3165);
DISPLAY 0.659574 (985 -3165);
PAINT MONO (985 -3165);
DISPLAY INVISIBLE (985 -3165);
FORCEPROP 1 LAST HDL_POWER P3V3_AUX
J 1
(975 -3075);
DISPLAY 0.872340 (975 -3075);
PAINT GREEN (975 -3075);
FORCEPROP 2 LAST CDS_LIB logical_power
J 0
(975 -3125);
DISPLAY INVISIBLE (975 -3125);
FORCEPROP 1 LAST PATH I66
J 0
(1025 -3100);
DISPLAY 0.872340 (1025 -3100);
PAINT AQUA (1025 -3100);
DISPLAY INVISIBLE (1025 -3100);
FORCEADD OFFPAGE..2
(4000 -3875);
FORCEPROP 2 LAST $XR0 214 
J 0
(4189 -3875);
DISPLAY 0.638298 (4189 -3875);
PAINT MONO (4189 -3875);
FORCEPROP 2 LAST CDS_LIB standard
J 0
(4000 -3875);
DISPLAY INVISIBLE (4000 -3875);
FORCEPROP 1 LAST COMMENT_BODY TRUE
J 0
(3955 -3970);
DISPLAY 0.872340 (3955 -3970);
PAINT GREEN (3955 -3970);
DISPLAY INVISIBLE (3955 -3970);
FORCEPROP 1 LAST OFFPAGE TRUE
J 0
(4325 -4000);
DISPLAY 0.872340 (4325 -4000);
DISPLAY INVISIBLE (4325 -4000);
FORCEPROP 2 LAST PATH I67
J 0
(4175 -3800);
DISPLAY 1.021277 (4175 -3800);
DISPLAY INVISIBLE (4175 -3800);
FORCEADD Q_RES..1
(-975 -3850);
FORCEPROP 1 LAST PART_NUMBER CS24702FB06
J 0
(-1400 -3850);
DISPLAY 0.510638 (-1400 -3850);
DISPLAY INVISIBLE (-1400 -3850);
FORCEPROP 1 LAST PACK_TYPE 0402LF
J 0
(-500 -3850);
DISPLAY 0.510638 (-500 -3850);
FORCEPROP 1 LAST WATTAGE 1/16W
J 2
(-650 -3850);
DISPLAY 0.510638 (-650 -3850);
FORCEPROP 1 LAST VALUE 4.7K
J 2
(-775 -3850);
DISPLAY 0.510638 (-775 -3850);
FORCEPROP 1 LAST TOLERANCE 1%
J 0
(-650 -3850);
DISPLAY 0.510638 (-650 -3850);
FORCEPROP 1 LAST MATERIAL EMPTY
J 0
(-600 -3850);
DISPLAY 0.510638 (-600 -3850);
PAINT RED (-600 -3850);
FORCEPROP 1 LAST $LOCATION R3612
J 0
(-1100 -3850);
DISPLAY 0.638298 (-1100 -3850);
FORCEPROP 1 LASTPIN (-1075 -3850) $PN 1
J 0
(-1063 -3838);
DISPLAY 0.787234 (-1063 -3838);
PAINT MONO (-1063 -3838);
FORCEPROP 1 LASTPIN (-875 -3850) $PN 2
J 0
(-913 -3838);
DISPLAY 0.787234 (-913 -3838);
PAINT MONO (-913 -3838);
FORCEPROP 1 LAST PATH I68
J 0
(-1025 -3700);
DISPLAY 0.978723 (-1025 -3700);
PAINT WHITE (-1025 -3700);
DISPLAY INVISIBLE (-1025 -3700);
FORCEPROP 2 LAST CDS_LIB pure_quanta
J 0
(-975 -3850);
DISPLAY INVISIBLE (-975 -3850);
FORCEPROP 0 LAST CDS_LOCATION R3612
J 0
(-1100 -3800);
DISPLAY 1.021277 (-1100 -3800);
DISPLAY INVISIBLE (-1100 -3800);
FORCEPROP 0 LAST $SEC 1
J 0
(-1100 -3800);
DISPLAY 0.680851 (-1100 -3800);
PAINT MONO (-1100 -3800);
DISPLAY INVISIBLE (-1100 -3800);
FORCEPROP 0 LAST CDS_SEC 1
J 0
(-1100 -3800);
DISPLAY 1.021277 (-1100 -3800);
DISPLAY INVISIBLE (-1100 -3800);
FORCEADD INA230AIRGTR..1
(1425 -4125);
FORCEPROP 1 LAST PART_NUMBER AL000230001
J 0
(1178 -3689);
DISPLAY 0.723404 (1178 -3689);
PAINT GREEN (1178 -3689);
DISPLAY INVISIBLE (1178 -3689);
FORCEPROP 2 LAST PART_TYPE SMLF
J 0
(1150 -3450);
DISPLAY 1.021277 (1150 -3450);
FORCEPROP 1 LAST MATERIAL IC
J 0
(1178 -3816);
DISPLAY 0.723404 (1178 -3816);
PAINT GREEN (1178 -3816);
FORCEPROP 2 LAST VALUE INA230AIRGTR
J 0
(1150 -3500);
DISPLAY 1.021277 (1150 -3500);
FORCEPROP 1 LAST $LOCATION U265
J 0
(1178 -3542);
DISPLAY 0.723404 (1178 -3542);
PAINT GREEN (1178 -3542);
FORCEPROP 0 LASTPIN (1025 -4025) $PN 2
J 2
(1015 -4015);
DISPLAY 0.680851 (1015 -4015);
PAINT MONO (1015 -4015);
FORCEPROP 0 LASTPIN (1025 -3975) $PN 1
J 2
(1015 -3965);
DISPLAY 0.680851 (1015 -3965);
PAINT MONO (1015 -3965);
FORCEPROP 0 LASTPIN (1825 -3875) $PN 3
J 0
(1835 -3865);
DISPLAY 0.680851 (1835 -3865);
PAINT MONO (1835 -3865);
FORCEPROP 0 LASTPIN (1025 -4275) $PN 11
J 2
(1015 -4265);
DISPLAY 0.680851 (1015 -4265);
PAINT MONO (1015 -4265);
FORCEPROP 0 LASTPIN (1825 -4325) $PN 10
J 0
(1835 -4315);
DISPLAY 0.680851 (1835 -4315);
PAINT MONO (1835 -4315);
FORCEPROP 0 LASTPIN (1025 -4325) $PN 13
J 2
(1015 -4315);
DISPLAY 0.680851 (1015 -4315);
PAINT MONO (1015 -4315);
FORCEPROP 0 LASTPIN (1025 -4375) $PN 12
J 2
(1015 -4365);
DISPLAY 0.680851 (1015 -4365);
PAINT MONO (1015 -4365);
FORCEPROP 0 LASTPIN (1825 -3975) $PN 6
J 0
(1835 -3965);
DISPLAY 0.680851 (1835 -3965);
PAINT MONO (1835 -3965);
FORCEPROP 0 LASTPIN (1825 -4025) $PN 7
J 0
(1835 -4015);
DISPLAY 0.680851 (1835 -4015);
PAINT MONO (1835 -4015);
FORCEPROP 0 LASTPIN (1825 -4075) $PN 8
J 0
(1835 -4065);
DISPLAY 0.680851 (1835 -4065);
PAINT MONO (1835 -4065);
FORCEPROP 0 LASTPIN (1825 -4125) $PN 14
J 0
(1835 -4115);
DISPLAY 0.680851 (1835 -4115);
PAINT MONO (1835 -4115);
FORCEPROP 0 LASTPIN (1825 -4175) $PN 15
J 0
(1835 -4165);
DISPLAY 0.680851 (1835 -4165);
PAINT MONO (1835 -4165);
FORCEPROP 0 LASTPIN (1825 -4225) $PN 16
J 0
(1835 -4215);
DISPLAY 0.680851 (1835 -4215);
PAINT MONO (1835 -4215);
FORCEPROP 0 LASTPIN (1025 -4125) $PN 5
J 2
(1015 -4115);
DISPLAY 0.680851 (1015 -4115);
PAINT MONO (1015 -4115);
FORCEPROP 0 LASTPIN (1025 -4175) $PN 4
J 2
(1015 -4165);
DISPLAY 0.680851 (1015 -4165);
PAINT MONO (1015 -4165);
FORCEPROP 0 LASTPIN (1825 -4375) $PN TH
J 0
(1835 -4365);
DISPLAY 0.680851 (1835 -4365);
PAINT MONO (1835 -4365);
FORCEPROP 0 LASTPIN (1025 -3875) $PN 9
J 2
(1015 -3865);
DISPLAY 0.680851 (1015 -3865);
PAINT MONO (1015 -3865);
FORCEPROP 2 LAST CDS_LIB pure_quanta
J 0
(1425 -4125);
DISPLAY INVISIBLE (1425 -4125);
FORCEPROP 1 LAST CDS_LMAN_SYM_OUTLINE -250,300,250,-300
J 0
(1425 -4125);
DISPLAY 0.468085 (1425 -4125);
PAINT GREEN (1425 -4125);
DISPLAY INVISIBLE (1425 -4125);
FORCEPROP 1 LAST PATH I69
J 0
(1425 -4125);
DISPLAY 0.723404 (1425 -4125);
PAINT GREEN (1425 -4125);
DISPLAY INVISIBLE (1425 -4125);
FORCEPROP 1 LAST NEEDS_NO_SIZE TRUE
J 0
(1425 -4125);
DISPLAY 0.723404 (1425 -4125);
PAINT GREEN (1425 -4125);
DISPLAY INVISIBLE (1425 -4125);
FORCEPROP 0 LAST CDS_LOCATION U265
J 0
(1150 -3400);
DISPLAY 1.021277 (1150 -3400);
DISPLAY INVISIBLE (1150 -3400);
FORCEPROP 0 LAST $SEC 1
J 0
(1150 -3400);
DISPLAY 0.680851 (1150 -3400);
PAINT MONO (1150 -3400);
DISPLAY INVISIBLE (1150 -3400);
FORCEPROP 0 LAST CDS_SEC 1
J 0
(1150 -3400);
DISPLAY 1.021277 (1150 -3400);
DISPLAY INVISIBLE (1150 -3400);
FORCEADD Q_CAP..1
(75 -2725);
FORCEPROP 1 LAST PART_NUMBER CH4104K1B00
J 0
(125 -2775);
DISPLAY 0.510638 (125 -2775);
DISPLAY INVISIBLE (125 -2775);
FORCEPROP 1 LAST TOLERANCE 10%
J 0
(125 -2725);
DISPLAY 0.510638 (125 -2725);
FORCEPROP 1 LAST MATERIAL X7R
J 0
(125 -2750);
DISPLAY 0.510638 (125 -2750);
FORCEPROP 1 LAST VOLTAGE 25V
J 0
(125 -2700);
DISPLAY 0.510638 (125 -2700);
FORCEPROP 1 LAST VALUE 0.1UF
J 0
(125 -2675);
DISPLAY 0.510638 (125 -2675);
FORCEPROP 1 LAST PACK_TYPE 0402
J 0
(125 -2800);
DISPLAY 0.510638 (125 -2800);
FORCEPROP 1 LAST $LOCATION C2021
J 0
(125 -2625);
DISPLAY 0.978723 (125 -2625);
FORCEPROP 1 LASTPIN (75 -2625) $PN 1
J 0
(85 -2645);
DISPLAY 0.787234 (85 -2645);
PAINT MONO (85 -2645);
FORCEPROP 1 LASTPIN (75 -2825) $PN 2
J 0
(85 -2845);
DISPLAY 0.787234 (85 -2845);
PAINT MONO (85 -2845);
FORCEPROP 2 LAST CDS_LIB pure_quanta
J 0
(75 -2725);
DISPLAY INVISIBLE (75 -2725);
FORCEPROP 1 LAST PATH I71
J 0
(125 -2575);
DISPLAY 0.978723 (125 -2575);
PAINT WHITE (125 -2575);
DISPLAY INVISIBLE (125 -2575);
FORCEPROP 0 LAST CDS_LOCATION C2021
J 0
(125 -2575);
DISPLAY 1.021277 (125 -2575);
DISPLAY INVISIBLE (125 -2575);
FORCEPROP 0 LAST $SEC 1
J 0
(125 -2575);
DISPLAY 0.680851 (125 -2575);
PAINT MONO (125 -2575);
DISPLAY INVISIBLE (125 -2575);
FORCEPROP 0 LAST CDS_SEC 1
J 0
(125 -2575);
DISPLAY 1.021277 (125 -2575);
DISPLAY INVISIBLE (125 -2575);
FORCEADD Q_CAP..1
(200 -4875);
FORCEPROP 1 LAST PART_NUMBER CH4104K1B00
J 0
(250 -4925);
DISPLAY 0.510638 (250 -4925);
DISPLAY INVISIBLE (250 -4925);
FORCEPROP 1 LAST VALUE 0.1UF
J 0
(250 -4825);
DISPLAY 0.510638 (250 -4825);
FORCEPROP 1 LAST VOLTAGE 25V
J 0
(250 -4850);
DISPLAY 0.510638 (250 -4850);
FORCEPROP 1 LAST TOLERANCE 10%
J 0
(250 -4875);
DISPLAY 0.510638 (250 -4875);
FORCEPROP 1 LAST MATERIAL X7R
J 0
(250 -4900);
DISPLAY 0.510638 (250 -4900);
FORCEPROP 1 LAST PACK_TYPE 0402
J 0
(250 -4950);
DISPLAY 0.510638 (250 -4950);
FORCEPROP 1 LAST $LOCATION C2022
J 0
(250 -4775);
DISPLAY 0.978723 (250 -4775);
FORCEPROP 1 LASTPIN (200 -4775) $PN 1
J 0
(210 -4795);
DISPLAY 0.787234 (210 -4795);
PAINT MONO (210 -4795);
FORCEPROP 1 LASTPIN (200 -4975) $PN 2
J 0
(210 -4995);
DISPLAY 0.787234 (210 -4995);
PAINT MONO (210 -4995);
FORCEPROP 1 LAST PATH I72
J 0
(250 -4725);
DISPLAY 0.978723 (250 -4725);
PAINT WHITE (250 -4725);
DISPLAY INVISIBLE (250 -4725);
FORCEPROP 2 LAST CDS_LIB pure_quanta
J 0
(200 -4875);
DISPLAY INVISIBLE (200 -4875);
FORCEPROP 0 LAST CDS_LOCATION C2022
J 0
(250 -4725);
DISPLAY 1.021277 (250 -4725);
DISPLAY INVISIBLE (250 -4725);
FORCEPROP 0 LAST $SEC 1
J 0
(250 -4725);
DISPLAY 0.680851 (250 -4725);
PAINT MONO (250 -4725);
DISPLAY INVISIBLE (250 -4725);
FORCEPROP 0 LAST CDS_SEC 1
J 0
(250 -4725);
DISPLAY 1.021277 (250 -4725);
DISPLAY INVISIBLE (250 -4725);
FORCEADD UNIVERSAL_POWER..1
(-1675 -2225);
FORCEPROP 3 LASTPIN (-1675 -2275) SIG_NAME P3V3\g
J 0
(-1665 -2265);
DISPLAY 0.659574 (-1665 -2265);
PAINT MONO (-1665 -2265);
DISPLAY INVISIBLE (-1665 -2265);
FORCEPROP 1 LAST HDL_POWER P3V3
J 1
(-1675 -2175);
DISPLAY 0.872340 (-1675 -2175);
PAINT GREEN (-1675 -2175);
FORCEPROP 2 LAST CDS_LIB logical_power
J 0
(-1675 -2225);
DISPLAY INVISIBLE (-1675 -2225);
FORCEPROP 1 LAST PATH I76
J 0
(-1625 -2200);
DISPLAY 0.872340 (-1625 -2200);
PAINT AQUA (-1625 -2200);
DISPLAY INVISIBLE (-1625 -2200);
FORCEADD UNIVERSAL_POWER..1
(75 -1025);
FORCEPROP 3 LASTPIN (75 -1075) SIG_NAME P3V3_AUX\g
J 0
(85 -1065);
DISPLAY 0.659574 (85 -1065);
PAINT MONO (85 -1065);
DISPLAY INVISIBLE (85 -1065);
FORCEPROP 1 LAST HDL_POWER P3V3_AUX
J 1
(75 -975);
DISPLAY 0.872340 (75 -975);
PAINT GREEN (75 -975);
FORCEPROP 1 LAST PATH I85
J 0
(125 -1000);
DISPLAY 0.872340 (125 -1000);
PAINT AQUA (125 -1000);
DISPLAY INVISIBLE (125 -1000);
FORCEPROP 2 LAST CDS_LIB logical_power
J 0
(75 -1025);
DISPLAY INVISIBLE (75 -1025);
FORCEADD Q_RES..2
(75 -1325);
FORCEPROP 1 LAST PART_NUMBER CS24702FB06
J 0
(115 -1450);
DISPLAY 0.510638 (115 -1450);
DISPLAY INVISIBLE (115 -1450);
FORCEPROP 1 LAST WATTAGE 1/16W
J 0
(115 -1350);
DISPLAY 0.510638 (115 -1350);
FORCEPROP 1 LAST VALUE 4.7K
J 0
(120 -1250);
DISPLAY 0.510638 (120 -1250);
FORCEPROP 1 LAST TOLERANCE 1%
J 0
(120 -1300);
DISPLAY 0.510638 (120 -1300);
FORCEPROP 1 LAST PACK_TYPE 0402LF
J 0
(115 -1500);
DISPLAY 0.510638 (115 -1500);
FORCEPROP 1 LAST MATERIAL CHIP
J 0
(115 -1400);
DISPLAY 0.510638 (115 -1400);
FORCEPROP 1 LAST $LOCATION R3623
J 0
(120 -1200);
DISPLAY 0.978723 (120 -1200);
FORCEPROP 1 LASTPIN (75 -1225) $PN 1
J 0
(80 -1263);
DISPLAY 0.787234 (80 -1263);
PAINT MONO (80 -1263);
FORCEPROP 1 LASTPIN (75 -1425) $PN 2
J 0
(80 -1415);
DISPLAY 0.787234 (80 -1415);
PAINT MONO (80 -1415);
FORCEPROP 1 LAST PATH I86
J 0
(125 -1150);
DISPLAY 0.978723 (125 -1150);
PAINT WHITE (125 -1150);
DISPLAY INVISIBLE (125 -1150);
FORCEPROP 2 LAST CDS_LIB pure_quanta
J 0
(75 -1325);
DISPLAY INVISIBLE (75 -1325);
FORCEPROP 0 LAST CDS_LOCATION R3623
J 0
(125 -1150);
DISPLAY 1.021277 (125 -1150);
DISPLAY INVISIBLE (125 -1150);
FORCEPROP 0 LAST $SEC 1
J 0
(125 -1150);
DISPLAY 0.680851 (125 -1150);
PAINT MONO (125 -1150);
DISPLAY INVISIBLE (125 -1150);
FORCEPROP 0 LAST CDS_SEC 1
J 0
(125 -1150);
DISPLAY 1.021277 (125 -1150);
DISPLAY INVISIBLE (125 -1150);
FORCEADD Q_RES..2
(-225 -1325);
FORCEPROP 1 LAST PART_NUMBER CS24702FB06
J 0
(-185 -1450);
DISPLAY 0.510638 (-185 -1450);
DISPLAY INVISIBLE (-185 -1450);
FORCEPROP 1 LAST VALUE 4.7K
J 0
(-180 -1250);
DISPLAY 0.510638 (-180 -1250);
FORCEPROP 1 LAST TOLERANCE 1%
J 0
(-180 -1300);
DISPLAY 0.510638 (-180 -1300);
FORCEPROP 1 LAST PACK_TYPE 0402LF
J 0
(-185 -1500);
DISPLAY 0.510638 (-185 -1500);
FORCEPROP 1 LAST WATTAGE 1/16W
J 0
(-185 -1350);
DISPLAY 0.510638 (-185 -1350);
FORCEPROP 1 LAST MATERIAL EMPTY
J 0
(-185 -1400);
DISPLAY 0.510638 (-185 -1400);
PAINT RED (-185 -1400);
FORCEPROP 1 LAST $LOCATION R3621
J 0
(-180 -1200);
DISPLAY 0.978723 (-180 -1200);
FORCEPROP 1 LASTPIN (-225 -1225) $PN 1
J 0
(-220 -1263);
DISPLAY 0.787234 (-220 -1263);
PAINT MONO (-220 -1263);
FORCEPROP 1 LASTPIN (-225 -1425) $PN 2
J 0
(-220 -1415);
DISPLAY 0.787234 (-220 -1415);
PAINT MONO (-220 -1415);
FORCEPROP 1 LAST PATH I87
J 0
(-175 -1150);
DISPLAY 0.978723 (-175 -1150);
PAINT WHITE (-175 -1150);
DISPLAY INVISIBLE (-175 -1150);
FORCEPROP 2 LAST CDS_LIB pure_quanta
J 0
(-225 -1325);
DISPLAY INVISIBLE (-225 -1325);
FORCEPROP 0 LAST CDS_LOCATION R3621
J 0
(-175 -1150);
DISPLAY 1.021277 (-175 -1150);
DISPLAY INVISIBLE (-175 -1150);
FORCEPROP 0 LAST $SEC 1
J 0
(-175 -1150);
DISPLAY 0.680851 (-175 -1150);
PAINT MONO (-175 -1150);
DISPLAY INVISIBLE (-175 -1150);
FORCEPROP 0 LAST CDS_SEC 1
J 0
(-175 -1150);
DISPLAY 1.021277 (-175 -1150);
DISPLAY INVISIBLE (-175 -1150);
FORCEADD UNIVERSAL_POWER..1
(125 -3225);
FORCEPROP 3 LASTPIN (125 -3275) SIG_NAME P3V3_AUX\g
J 0
(135 -3265);
DISPLAY 0.659574 (135 -3265);
PAINT MONO (135 -3265);
DISPLAY INVISIBLE (135 -3265);
FORCEPROP 1 LAST HDL_POWER P3V3_AUX
J 1
(125 -3175);
DISPLAY 0.872340 (125 -3175);
PAINT GREEN (125 -3175);
FORCEPROP 1 LAST PATH I88
J 0
(175 -3200);
DISPLAY 0.872340 (175 -3200);
PAINT AQUA (175 -3200);
DISPLAY INVISIBLE (175 -3200);
FORCEPROP 2 LAST CDS_LIB logical_power
J 0
(125 -3225);
DISPLAY INVISIBLE (125 -3225);
FORCEADD Q_RES..2
(125 -3525);
FORCEPROP 1 LAST PART_NUMBER CS24702FB06
J 0
(165 -3650);
DISPLAY 0.510638 (165 -3650);
DISPLAY INVISIBLE (165 -3650);
FORCEPROP 1 LAST TOLERANCE 1%
J 0
(170 -3500);
DISPLAY 0.510638 (170 -3500);
FORCEPROP 1 LAST VALUE 4.7K
J 0
(170 -3450);
DISPLAY 0.510638 (170 -3450);
FORCEPROP 1 LAST MATERIAL CHIP
J 0
(165 -3600);
DISPLAY 0.510638 (165 -3600);
FORCEPROP 1 LAST PACK_TYPE 0402LF
J 0
(165 -3700);
DISPLAY 0.510638 (165 -3700);
FORCEPROP 1 LAST WATTAGE 1/16W
J 0
(165 -3550);
DISPLAY 0.510638 (165 -3550);
FORCEPROP 1 LAST $LOCATION R3624
J 0
(170 -3400);
DISPLAY 0.978723 (170 -3400);
FORCEPROP 1 LASTPIN (125 -3425) $PN 1
J 0
(130 -3463);
DISPLAY 0.787234 (130 -3463);
PAINT MONO (130 -3463);
FORCEPROP 1 LASTPIN (125 -3625) $PN 2
J 0
(130 -3615);
DISPLAY 0.787234 (130 -3615);
PAINT MONO (130 -3615);
FORCEPROP 2 LAST CDS_LIB pure_quanta
J 0
(125 -3525);
DISPLAY INVISIBLE (125 -3525);
FORCEPROP 1 LAST PATH I89
J 0
(175 -3350);
DISPLAY 0.978723 (175 -3350);
PAINT WHITE (175 -3350);
DISPLAY INVISIBLE (175 -3350);
FORCEPROP 0 LAST CDS_LOCATION R3624
J 0
(175 -3350);
DISPLAY 1.021277 (175 -3350);
DISPLAY INVISIBLE (175 -3350);
FORCEPROP 0 LAST $SEC 1
J 0
(175 -3350);
DISPLAY 0.680851 (175 -3350);
PAINT MONO (175 -3350);
DISPLAY INVISIBLE (175 -3350);
FORCEPROP 0 LAST CDS_SEC 1
J 0
(175 -3350);
DISPLAY 1.021277 (175 -3350);
DISPLAY INVISIBLE (175 -3350);
FORCEADD Q_RES..2
(-175 -3525);
FORCEPROP 1 LAST PART_NUMBER CS24702FB06
J 0
(-135 -3650);
DISPLAY 0.510638 (-135 -3650);
DISPLAY INVISIBLE (-135 -3650);
FORCEPROP 1 LAST MATERIAL CHIP
J 0
(-135 -3600);
DISPLAY 0.510638 (-135 -3600);
FORCEPROP 1 LAST VALUE 4.7K
J 0
(-130 -3450);
DISPLAY 0.510638 (-130 -3450);
FORCEPROP 1 LAST PACK_TYPE 0402LF
J 0
(-135 -3700);
DISPLAY 0.510638 (-135 -3700);
FORCEPROP 1 LAST TOLERANCE 1%
J 0
(-130 -3500);
DISPLAY 0.510638 (-130 -3500);
FORCEPROP 1 LAST WATTAGE 1/16W
J 0
(-135 -3550);
DISPLAY 0.510638 (-135 -3550);
FORCEPROP 1 LAST $LOCATION R3622
J 0
(-130 -3400);
DISPLAY 0.978723 (-130 -3400);
FORCEPROP 1 LASTPIN (-175 -3425) $PN 1
J 0
(-170 -3463);
DISPLAY 0.787234 (-170 -3463);
PAINT MONO (-170 -3463);
FORCEPROP 1 LASTPIN (-175 -3625) $PN 2
J 0
(-170 -3615);
DISPLAY 0.787234 (-170 -3615);
PAINT MONO (-170 -3615);
FORCEPROP 1 LAST PATH I90
J 0
(-125 -3350);
DISPLAY 0.978723 (-125 -3350);
PAINT WHITE (-125 -3350);
DISPLAY INVISIBLE (-125 -3350);
FORCEPROP 2 LAST CDS_LIB pure_quanta
J 0
(-175 -3525);
DISPLAY INVISIBLE (-175 -3525);
FORCEPROP 0 LAST CDS_LOCATION R3622
J 0
(-125 -3350);
DISPLAY 1.021277 (-125 -3350);
DISPLAY INVISIBLE (-125 -3350);
FORCEPROP 0 LAST $SEC 1
J 0
(-125 -3350);
DISPLAY 0.680851 (-125 -3350);
PAINT MONO (-125 -3350);
DISPLAY INVISIBLE (-125 -3350);
FORCEPROP 0 LAST CDS_SEC 1
J 0
(-125 -3350);
DISPLAY 1.021277 (-125 -3350);
DISPLAY INVISIBLE (-125 -3350);
FORCEADD INA230AIRGTR..1
(1725 125);
FORCEPROP 1 LAST PART_NUMBER AL000230001
J 0
(1478 561);
DISPLAY 0.723404 (1478 561);
PAINT GREEN (1478 561);
DISPLAY INVISIBLE (1478 561);
FORCEPROP 2 LAST VALUE INA230AIRGTR
J 0
(1450 750);
DISPLAY 1.021277 (1450 750);
FORCEPROP 1 LAST MATERIAL IC
J 0
(1478 434);
DISPLAY 0.723404 (1478 434);
PAINT GREEN (1478 434);
FORCEPROP 2 LAST PART_TYPE SMLF
J 0
(1450 800);
DISPLAY 1.021277 (1450 800);
FORCEPROP 1 LAST $LOCATION U263
J 0
(1478 708);
DISPLAY 0.723404 (1478 708);
PAINT GREEN (1478 708);
FORCEPROP 0 LASTPIN (1325 225) $PN 2
J 2
(1315 235);
DISPLAY 0.680851 (1315 235);
PAINT MONO (1315 235);
FORCEPROP 0 LASTPIN (1325 275) $PN 1
J 2
(1315 285);
DISPLAY 0.680851 (1315 285);
PAINT MONO (1315 285);
FORCEPROP 0 LASTPIN (2125 375) $PN 3
J 0
(2135 385);
DISPLAY 0.680851 (2135 385);
PAINT MONO (2135 385);
FORCEPROP 0 LASTPIN (1325 -25) $PN 11
J 2
(1315 -15);
DISPLAY 0.680851 (1315 -15);
PAINT MONO (1315 -15);
FORCEPROP 0 LASTPIN (2125 -75) $PN 10
J 0
(2135 -65);
DISPLAY 0.680851 (2135 -65);
PAINT MONO (2135 -65);
FORCEPROP 0 LASTPIN (1325 -75) $PN 13
J 2
(1315 -65);
DISPLAY 0.680851 (1315 -65);
PAINT MONO (1315 -65);
FORCEPROP 0 LASTPIN (1325 -125) $PN 12
J 2
(1315 -115);
DISPLAY 0.680851 (1315 -115);
PAINT MONO (1315 -115);
FORCEPROP 0 LASTPIN (2125 275) $PN 6
J 0
(2135 285);
DISPLAY 0.680851 (2135 285);
PAINT MONO (2135 285);
FORCEPROP 0 LASTPIN (2125 225) $PN 7
J 0
(2135 235);
DISPLAY 0.680851 (2135 235);
PAINT MONO (2135 235);
FORCEPROP 0 LASTPIN (2125 175) $PN 8
J 0
(2135 185);
DISPLAY 0.680851 (2135 185);
PAINT MONO (2135 185);
FORCEPROP 0 LASTPIN (2125 125) $PN 14
J 0
(2135 135);
DISPLAY 0.680851 (2135 135);
PAINT MONO (2135 135);
FORCEPROP 0 LASTPIN (2125 75) $PN 15
J 0
(2135 85);
DISPLAY 0.680851 (2135 85);
PAINT MONO (2135 85);
FORCEPROP 0 LASTPIN (2125 25) $PN 16
J 0
(2135 35);
DISPLAY 0.680851 (2135 35);
PAINT MONO (2135 35);
FORCEPROP 0 LASTPIN (1325 125) $PN 5
J 2
(1315 135);
DISPLAY 0.680851 (1315 135);
PAINT MONO (1315 135);
FORCEPROP 0 LASTPIN (1325 75) $PN 4
J 2
(1315 85);
DISPLAY 0.680851 (1315 85);
PAINT MONO (1315 85);
FORCEPROP 0 LASTPIN (2125 -125) $PN TH
J 0
(2135 -115);
DISPLAY 0.680851 (2135 -115);
PAINT MONO (2135 -115);
FORCEPROP 0 LASTPIN (1325 375) $PN 9
J 2
(1315 385);
DISPLAY 0.680851 (1315 385);
PAINT MONO (1315 385);
FORCEPROP 1 LAST NEEDS_NO_SIZE TRUE
J 0
(1725 125);
DISPLAY 0.723404 (1725 125);
PAINT GREEN (1725 125);
DISPLAY INVISIBLE (1725 125);
FORCEPROP 1 LAST PATH I94
J 0
(1725 125);
DISPLAY 0.723404 (1725 125);
PAINT GREEN (1725 125);
DISPLAY INVISIBLE (1725 125);
FORCEPROP 1 LAST CDS_LMAN_SYM_OUTLINE -250,300,250,-300
J 0
(1725 125);
DISPLAY 0.468085 (1725 125);
PAINT GREEN (1725 125);
DISPLAY INVISIBLE (1725 125);
FORCEPROP 2 LAST CDS_LIB pure_quanta
J 0
(1725 125);
DISPLAY INVISIBLE (1725 125);
FORCEPROP 0 LAST CDS_LOCATION U263
J 0
(1450 850);
DISPLAY 1.021277 (1450 850);
DISPLAY INVISIBLE (1450 850);
FORCEPROP 0 LAST $SEC 1
J 0
(1450 850);
DISPLAY 0.680851 (1450 850);
PAINT MONO (1450 850);
DISPLAY INVISIBLE (1450 850);
FORCEPROP 0 LAST CDS_SEC 1
J 0
(1450 850);
DISPLAY 1.021277 (1450 850);
DISPLAY INVISIBLE (1450 850);
FORCEADD OFFPAGE..2
(4525 375);
FORCEPROP 2 LAST $XR0 214 
J 0
(4714 375);
DISPLAY 0.638298 (4714 375);
PAINT MONO (4714 375);
FORCEPROP 1 LAST OFFPAGE TRUE
J 0
(4850 250);
DISPLAY 0.872340 (4850 250);
DISPLAY INVISIBLE (4850 250);
FORCEPROP 1 LAST COMMENT_BODY TRUE
J 0
(4480 280);
DISPLAY 0.872340 (4480 280);
PAINT GREEN (4480 280);
DISPLAY INVISIBLE (4480 280);
FORCEPROP 2 LAST CDS_LIB standard
J 0
(4525 375);
DISPLAY INVISIBLE (4525 375);
FORCEPROP 2 LAST PATH I95
J 0
(4725 425);
DISPLAY 1.021277 (4725 425);
DISPLAY INVISIBLE (4725 425);
FORCEADD Q_RES..1
(3275 375);
FORCEPROP 1 LAST PART_NUMBER CS00002JB13
J 0
(3000 250);
DISPLAY 0.723404 (3000 250);
PAINT WHITE (3000 250);
DISPLAY INVISIBLE (3000 250);
FORCEPROP 1 LAST PACK_TYPE 0402LF
J 0
(3575 375);
DISPLAY 0.574468 (3575 375);
FORCEPROP 1 LAST VALUE 0
J 2
(3425 375);
DISPLAY 0.574468 (3425 375);
FORCEPROP 1 LAST MATERIAL CHIP
J 0
(3450 375);
DISPLAY 0.574468 (3450 375);
FORCEPROP 1 LAST $LOCATION R3559
J 0
(3100 375);
DISPLAY 0.510638 (3100 375);
FORCEPROP 1 LASTPIN (3175 375) $PN 1
J 0
(3187 387);
DISPLAY 0.787234 (3187 387);
PAINT MONO (3187 387);
FORCEPROP 1 LASTPIN (3375 375) $PN 2
J 0
(3337 387);
DISPLAY 0.787234 (3337 387);
PAINT MONO (3337 387);
FORCEPROP 1 LAST WATTAGE 1/16W
J 2
(3350 300);
DISPLAY 0.723404 (3350 300);
PAINT SKYBLUE (3350 300);
DISPLAY INVISIBLE (3350 300);
FORCEPROP 1 LAST TOLERANCE 5%
J 0
(3075 300);
DISPLAY 0.723404 (3075 300);
PAINT SKYBLUE (3075 300);
DISPLAY INVISIBLE (3075 300);
FORCEPROP 2 LAST CDS_LIB pure_quanta
J 0
(3275 375);
DISPLAY INVISIBLE (3275 375);
FORCEPROP 1 LAST PATH I96
J 0
(3225 525);
DISPLAY 0.978723 (3225 525);
PAINT WHITE (3225 525);
DISPLAY INVISIBLE (3225 525);
FORCEPROP 0 LAST CDS_LOCATION R3559
J 0
(3575 425);
DISPLAY 1.021277 (3575 425);
DISPLAY INVISIBLE (3575 425);
FORCEPROP 0 LAST $SEC 1
J 0
(3575 425);
DISPLAY 0.680851 (3575 425);
PAINT MONO (3575 425);
DISPLAY INVISIBLE (3575 425);
FORCEPROP 0 LAST CDS_SEC 1
J 0
(3575 425);
DISPLAY 1.021277 (3575 425);
DISPLAY INVISIBLE (3575 425);
FORCEADD UNIVERSAL_POWER..1
(1275 1125);
FORCEPROP 3 LASTPIN (1275 1075) SIG_NAME P3V3_AUX\g
J 0
(1285 1085);
DISPLAY 0.659574 (1285 1085);
PAINT MONO (1285 1085);
DISPLAY INVISIBLE (1285 1085);
FORCEPROP 1 LAST HDL_POWER P3V3_AUX
J 1
(1275 1175);
DISPLAY 0.872340 (1275 1175);
PAINT GREEN (1275 1175);
FORCEPROP 2 LAST CDS_LIB logical_power
J 0
(1275 1125);
DISPLAY INVISIBLE (1275 1125);
FORCEPROP 1 LAST PATH I97
J 0
(1325 1150);
DISPLAY 0.872340 (1325 1150);
PAINT AQUA (1325 1150);
DISPLAY INVISIBLE (1325 1150);
FORCEADD Q_CAP..1
(1025 725);
FORCEPROP 1 LAST PART_NUMBER CH4104K1B00
J 0
(1075 575);
DISPLAY 0.808511 (1075 575);
DISPLAY INVISIBLE (1075 575);
FORCEPROP 1 LAST MATERIAL X7R
J 0
(1075 625);
DISPLAY 0.638298 (1075 625);
FORCEPROP 1 LAST TOLERANCE 10%
J 0
(1075 675);
DISPLAY 0.638298 (1075 675);
FORCEPROP 1 LAST VOLTAGE 25V
J 0
(1075 725);
DISPLAY 0.638298 (1075 725);
FORCEPROP 1 LAST VALUE 0.1UF
J 0
(1075 775);
DISPLAY 0.638298 (1075 775);
FORCEPROP 1 LAST PACK_TYPE 0402
J 0
(1075 575);
DISPLAY 0.638298 (1075 575);
FORCEPROP 1 LAST $LOCATION C2012
J 0
(1075 825);
DISPLAY 0.978723 (1075 825);
FORCEPROP 1 LASTPIN (1025 825) $PN 1
J 0
(1035 805);
DISPLAY 0.787234 (1035 805);
PAINT MONO (1035 805);
FORCEPROP 1 LASTPIN (1025 625) $PN 2
J 0
(1035 605);
DISPLAY 0.787234 (1035 605);
PAINT MONO (1035 605);
FORCEPROP 2 LAST CDS_LIB pure_quanta
J 0
(1025 725);
DISPLAY INVISIBLE (1025 725);
FORCEPROP 1 LAST PATH I98
J 0
(1075 875);
DISPLAY 0.978723 (1075 875);
PAINT WHITE (1075 875);
DISPLAY INVISIBLE (1075 875);
FORCEPROP 0 LAST CDS_LOCATION C2012
J 0
(1075 875);
DISPLAY 1.021277 (1075 875);
DISPLAY INVISIBLE (1075 875);
FORCEPROP 0 LAST $SEC 1
J 0
(1075 875);
DISPLAY 0.680851 (1075 875);
PAINT MONO (1075 875);
DISPLAY INVISIBLE (1075 875);
FORCEPROP 0 LAST CDS_SEC 1
J 0
(1075 875);
DISPLAY 1.021277 (1075 875);
DISPLAY INVISIBLE (1075 875);
FORCEADD UNIVERSAL_GND..1
(1025 450);
FORCEPROP 3 LASTPIN (1025 500) SIG_NAME GND\g
J 0
(1035 510);
DISPLAY 0.659574 (1035 510);
PAINT MONO (1035 510);
DISPLAY INVISIBLE (1035 510);
FORCEPROP 1 LAST HDL_POWER GND
J 1
(1050 375);
DISPLAY 0.872340 (1050 375);
PAINT GREEN (1050 375);
DISPLAY INVISIBLE (1050 375);
FORCEPROP 2 LAST CDS_LIB logical_power
J 0
(1025 450);
DISPLAY INVISIBLE (1025 450);
FORCEPROP 1 LAST PATH I99
J 0
(1100 450);
DISPLAY 0.872340 (1100 450);
PAINT AQUA (1100 450);
DISPLAY INVISIBLE (1100 450);
FORCEADD QUANTA_TITLE_BLOCK_C..1
(5375 -5375);
FORCEPROP 0 LAST CDS_CON_LAST_MODIFIED Fri Aug 25 14:02:43 2023
J 0
(3490 -5360);
DISPLAY INVISIBLE (3490 -5360);
FORCEPROP 1 LAST CUSTOM_TXT_CDS <CON_LAST_MODIFIED>
J 0
(3490 -5360);
DISPLAY 0.978723 (3490 -5360);
FORCEPROP 2 LAST CUSTOM_TXT_CDS <XR_PAGE_TITLE>
J 0
(-2515 -125);
DISPLAY 0.638298 (-2515 -125);
PAINT PINK (-2515 -125);
DISPLAY INVISIBLE (-2515 -125);
FORCEPROP 1 LAST CUSTOM_TXT_CDS <NAME_2>
J 0
(2200 -5325);
FORCEPROP 1 LAST CUSTOM_TXT_CDS <NAME_1>
J 0
(2200 -5200);
FORCEPROP 1 LAST CUSTOM_TXT_CDS <Q_NUMBER>
J 0
(3972 -5272);
DISPLAY 1.212766 (3972 -5272);
FORCEPROP 1 LAST CUSTOM_TXT_CDS <Q_PROJ>
J 0
(2993 -5273);
DISPLAY 1.212766 (2993 -5273);
FORCEPROP 1 LAST CUSTOM_TXT_CDS <Q_REV>
J 0
(5191 -5272);
DISPLAY 1.212766 (5191 -5272);
FORCEPROP 1 LAST CUSTOM_TXT_CDS <CON_PAGE_NUM> OF <CON_TOTAL_PAGES>
J 0
(4929 -5357);
DISPLAY 0.978723 (4929 -5357);
FORCEPROP 1 LAST Q_TITLE POWER MONITOR (2/2)
J 0
(-3850 -5300);
DISPLAY 2.446809 (-3850 -5300);
PAINT GREEN (-3850 -5300);
FORCEPROP 1 LAST Q_DEPT 
J 1
(1612 -5326);
DISPLAY 1.957447 (1612 -5326);
PAINT GREEN (1612 -5326);
FORCEPROP 2 LAST CDS_XR_PAGE_TITLE CR-172 : @S9S_MB_2U_LIB.S9S_MB_2U(SCH_1):PAGE172
J 0
(-2515 -125);
DISPLAY 0.638298 (-2515 -125);
PAINT PINK (-2515 -125);
DISPLAY INVISIBLE (-2515 -125);
FORCEPROP 2 LAST CDS_LIB pure_quanta
J 0
(5375 -5375);
DISPLAY INVISIBLE (5375 -5375);
FORCEPROP 1 LAST CDS_LMAN_SYM_OUTLINE -9475,6775,100,-125
J 0
(5375 -5375);
DISPLAY 0.468085 (5375 -5375);
PAINT GREEN (5375 -5375);
DISPLAY INVISIBLE (5375 -5375);
FORCEPROP 1 LAST COMMENT_BODY TRUE
J 0
(5387 -5388);
DISPLAY 0.978723 (5387 -5388);
PAINT GREEN (5387 -5388);
DISPLAY INVISIBLE (5387 -5388);
FORCEPROP 2 LAST PAGE_BORDER TRUE
J 0
(-2515 -125);
DISPLAY 0.638298 (-2515 -125);
PAINT PINK (-2515 -125);
DISPLAY INVISIBLE (-2515 -125);
FORCEADD DNS..2
(-500 525);
PAINT RED (-500 525);
FORCEPROP 1 LAST COMMENT_BODY TRUE
R 1
J 0
(-425 300);
DISPLAY 0.872340 (-425 300);
PAINT GREEN (-425 300);
DISPLAY INVISIBLE (-425 300);
FORCEPROP 2 LAST CDS_LIB mstr_misc
J 0
(-500 525);
DISPLAY INVISIBLE (-500 525);
FORCEADD DNS..2
(-1025 -1675);
PAINT RED (-1025 -1675);
FORCEPROP 2 LAST CDS_LIB mstr_misc
J 0
(-1025 -1675);
DISPLAY INVISIBLE (-1025 -1675);
FORCEPROP 1 LAST COMMENT_BODY TRUE
R 1
J 0
(-950 -1900);
DISPLAY 0.872340 (-950 -1900);
PAINT GREEN (-950 -1900);
DISPLAY INVISIBLE (-950 -1900);
FORCEADD DNS..2
(-225 -1350);
PAINT RED (-225 -1350);
FORCEPROP 1 LAST COMMENT_BODY TRUE
R 1
J 0
(-150 -1575);
DISPLAY 0.872340 (-150 -1575);
PAINT GREEN (-150 -1575);
DISPLAY INVISIBLE (-150 -1575);
FORCEPROP 2 LAST CDS_LIB mstr_misc
J 0
(-225 -1350);
DISPLAY INVISIBLE (-225 -1350);
FORCEADD DNS..2
(-950 -3925);
PAINT RED (-950 -3925);
FORCEPROP 2 LAST CDS_LIB mstr_misc
J 0
(-950 -3925);
DISPLAY INVISIBLE (-950 -3925);
FORCEPROP 1 LAST COMMENT_BODY TRUE
R 1
J 0
(-875 -4150);
DISPLAY 0.872340 (-875 -4150);
PAINT GREEN (-875 -4150);
DISPLAY INVISIBLE (-875 -4150);
FORCEADD DNS..2
(-950 -3850);
PAINT RED (-950 -3850);
FORCEPROP 2 LAST CDS_LIB mstr_misc
J 0
(-950 -3850);
DISPLAY INVISIBLE (-950 -3850);
FORCEPROP 1 LAST COMMENT_BODY TRUE
R 1
J 0
(-875 -4075);
DISPLAY 0.872340 (-875 -4075);
PAINT GREEN (-875 -4075);
DISPLAY INVISIBLE (-875 -4075);
WIRE 16 -1 (2575 -3325)(2575 -3275);
WIRE 16 -1 (2500 -1175)(2500 -1125);
WIRE 16 -1 (3075 925)(3075 975);
WIRE 16 -1 (1275 1075)(1275 950);
WIRE 16 -1 (-1550 -4525)(-1550 -4425);
WIRE 16 -1 (-1550 -4525)(-1725 -4525);
WIRE 16 -1 (75 -1075)(75 -1150);
WIRE 16 -1 (-2750 -2375)(-2750 -2275);
WIRE 16 -1 (-2450 -2375)(-2750 -2375);
WIRE 16 -1 (-1825 -1525)(-1825 -1575);
WIRE 16 -1 (-1675 -2375)(-1675 -2275);
WIRE 16 -1 (-1675 -2375)(-1850 -2375);
WIRE 16 -1 (-1400 575)(-1400 525);
WIRE 16 -1 (-2325 -275)(-2325 -175);
WIRE 16 -1 (-2025 -275)(-2325 -275);
WIRE 16 -1 (850 -1025)(850 -1150);
WIRE 16 -1 (125 -3275)(125 -3350);
WIRE 16 -1 (975 -3175)(975 -3300);
WIRE 16 -1 (-1700 -3675)(-1700 -3725);
WIRE 16 -1 (-2625 -4525)(-2625 -4425);
WIRE 16 -1 (-2325 -4525)(-2625 -4525);
WIRE 16 -1 (-1250 -275)(-1250 -175);
WIRE 16 -1 (-1425 -275)(-1250 -275);
WIRE 16 -1 (1950 -4375)(1950 -4725);
WIRE 16 -1 (1950 -4325)(1950 -4375);
WIRE 16 -1 (1825 -4375)(1950 -4375);
WIRE 16 -1 (1825 -2225)(1825 -2575);
WIRE 16 -1 (1825 -2175)(1825 -2225);
WIRE 16 -1 (1700 -2225)(1825 -2225);
WIRE 16 -1 (2250 -125)(2250 -475);
WIRE 16 -1 (2250 -75)(2250 -125);
WIRE 16 -1 (2125 -125)(2250 -125);
WIRE 16 -1 (1025 625)(1025 500);
WIRE 16 -1 (-950 450)(-950 525);
WIRE 16 -1 (-1650 200)(-1650 75);
WIRE 16 -1 (-2075 -1900)(-2075 -2025);
WIRE 16 -1 (-1475 -1825)(-1475 -1750);
WIRE 16 -1 (600 -1475)(600 -1600);
WIRE 16 -1 (-1950 -4050)(-1950 -4175);
WIRE 16 -1 (-1400 -4000)(-1400 -3925);
WIRE 16 -1 (725 -3625)(725 -3750);
WIRE 16 -1 (-2250 -2375)(-2450 -2375);
WIRE 16 -1 (-2450 -2850)(-2450 -2375);
WIRE 16 -1 (-2450 -2850)(-375 -2850);
WIRE 16 -1 (-2075 -1700)(-2075 -1575);
WIRE 16 -1 (-2075 -1575)(-1825 -1575);
WIRE 16 -1 (-1825 -1575)(-1825 -2125);
WIRE 16 -1 (900 -2125)(-1825 -2125);
WIRE 16 2175 (2375 -3075)(3050 -3075);
WIRE 16 2175 (3050 -3075)(3050 -3675);
WIRE 16 2175 (2375 -3075)(2375 -3675);
WIRE 16 2175 (2375 -3675)(3050 -3675);
WIRE 16 -1 (1700 -1825)(2325 -1825);
FORCEPROP 2 LAST SIG_NAME NC_INA230_4_NC0
J 0
(1840 -1815);
DISPLAY 0.638298 (1840 -1815);
PAINT WHITE (1840 -1815);
WIRE 16 -1 (2500 -1375)(2500 -1725);
WIRE 16 -1 (2500 -1725)(2600 -1725);
WIRE 16 -1 (1700 -1725)(2500 -1725);
FORCEPROP 2 LAST SIG_NAME M2_0_P3V3_ADC_ALERT_R
J 0
(1840 -1715);
DISPLAY 0.638298 (1840 -1715);
PAINT WHITE (1840 -1715);
WIRE 16 -1 (250 -750)(500 -750);
WIRE 16 -1 (500 -725)(500 -750);
WIRE 16 -1 (1200 -125)(1325 -125);
WIRE 16 -1 (1200 -750)(500 -750);
FORCEPROP 2 LAST SIG_NAME VSENSE_P12V_INA230_3_INN
J 0
(540 -740);
DISPLAY 0.510638 (540 -740);
PAINT WHITE (540 -740);
WIRE 16 -1 (1200 -750)(1200 -125);
WIRE 16 -1 (500 -525)(500 -475);
WIRE 16 -1 (500 -475)(250 -475);
WIRE 16 -1 (1100 -475)(500 -475);
FORCEPROP 2 LAST SIG_NAME VSENSE_P12V_INA230_3_INP
J 0
(515 -465);
DISPLAY 0.510638 (515 -465);
PAINT WHITE (515 -465);
WIRE 16 -1 (1100 -475)(1100 -75);
WIRE 16 -1 (1100 -75)(1325 -75);
WIRE 16 -1 (800 -1825)(900 -1825);
WIRE 16 -1 (800 -1675)(800 -1825);
WIRE 16 -1 (75 -1425)(75 -1675);
WIRE 16 -1 (75 -1675)(800 -1675);
FORCEPROP 2 LAST SIG_NAME INA230_4_A1
J 0
(190 -1665);
DISPLAY 0.638298 (190 -1665);
PAINT WHITE (190 -1665);
WIRE 16 -1 (-950 -1675)(75 -1675);
WIRE 16 -1 (-2025 -275)(-1850 -275);
WIRE 16 -1 (-2025 -750)(-2025 -275);
WIRE 16 -1 (-2025 -750)(50 -750);
WIRE 16 -1 (2125 -75)(2250 -75);
WIRE 16 -1 (2125 25)(2750 25);
FORCEPROP 2 LAST SIG_NAME NC_INA230_3_NC5
J 0
(2265 35);
DISPLAY 0.638298 (2265 35);
PAINT WHITE (2265 35);
WIRE 16 -1 (2125 75)(2750 75);
FORCEPROP 2 LAST SIG_NAME NC_INA230_3_NC4
J 0
(2265 85);
DISPLAY 0.638298 (2265 85);
PAINT WHITE (2265 85);
WIRE 16 -1 (2125 125)(2750 125);
FORCEPROP 2 LAST SIG_NAME NC_INA230_3_NC3
J 0
(2265 135);
DISPLAY 0.638298 (2265 135);
PAINT WHITE (2265 135);
WIRE 16 -1 (2125 175)(2750 175);
FORCEPROP 2 LAST SIG_NAME NC_INA230_3_NC2
J 0
(2265 185);
DISPLAY 0.638298 (2265 185);
PAINT WHITE (2265 185);
WIRE 16 -1 (2125 225)(2750 225);
FORCEPROP 2 LAST SIG_NAME NC_INA230_3_NC1
J 0
(2265 235);
DISPLAY 0.638298 (2265 235);
PAINT WHITE (2265 235);
WIRE 16 -1 (2125 275)(2750 275);
FORCEPROP 2 LAST SIG_NAME NC_INA230_3_NC0
J 0
(2265 285);
DISPLAY 0.638298 (2265 285);
PAINT WHITE (2265 285);
WIRE 16 -1 (3075 375)(3175 375);
WIRE 16 -1 (3075 725)(3075 375);
WIRE 16 -1 (2125 375)(3075 375);
FORCEPROP 2 LAST SIG_NAME OCP_V3_2_P3V3_ADC_ALERT_R
J 0
(2265 385);
DISPLAY 0.638298 (2265 385);
PAINT WHITE (2265 385);
WIRE 16 -1 (1700 -1975)(2325 -1975);
FORCEPROP 2 LAST SIG_NAME NC_INA230_4_NC3
J 0
(1840 -1965);
DISPLAY 0.638298 (1840 -1965);
PAINT WHITE (1840 -1965);
WIRE 16 -1 (1700 -2025)(2325 -2025);
FORCEPROP 2 LAST SIG_NAME NC_INA230_4_NC4
J 0
(1840 -2015);
DISPLAY 0.638298 (1840 -2015);
PAINT WHITE (1840 -2015);
WIRE 16 -1 (2575 -3875)(2725 -3875);
WIRE 16 -1 (2575 -3525)(2575 -3875);
WIRE 16 -1 (1825 -3875)(2575 -3875);
FORCEPROP 2 LAST SIG_NAME P12V_SCM_ADC_ALERT_R
J 0
(1965 -3865);
DISPLAY 0.638298 (1965 -3865);
PAINT WHITE (1965 -3865);
WIRE 16 -1 (1825 -4075)(2450 -4075);
FORCEPROP 2 LAST SIG_NAME NC_INA230_5_NC2
J 0
(1965 -4065);
DISPLAY 0.638298 (1965 -4065);
PAINT WHITE (1965 -4065);
WIRE 16 -1 (2925 -3875)(3950 -3875);
FORCEPROP 2 LAST SIG_NAME P12V_SCM_ADC_ALERT
J 0
(3315 -3865);
DISPLAY 0.638298 (3315 -3865);
PAINT WHITE (3315 -3865);
WIRE 16 -1 (1825 -4325)(1950 -4325);
WIRE 16 -1 (1825 -4025)(2450 -4025);
FORCEPROP 2 LAST SIG_NAME NC_INA230_5_NC1
J 0
(1965 -4015);
DISPLAY 0.638298 (1965 -4015);
PAINT WHITE (1965 -4015);
WIRE 16 -1 (1825 -3975)(2450 -3975);
FORCEPROP 2 LAST SIG_NAME NC_INA230_5_NC0
J 0
(1965 -3965);
DISPLAY 0.638298 (1965 -3965);
PAINT WHITE (1965 -3965);
WIRE 16 -1 (1825 -4175)(2450 -4175);
FORCEPROP 2 LAST SIG_NAME NC_INA230_5_NC4
J 0
(1965 -4165);
DISPLAY 0.638298 (1965 -4165);
PAINT WHITE (1965 -4165);
WIRE 16 -1 (1825 -4225)(2450 -4225);
FORCEPROP 2 LAST SIG_NAME NC_INA230_5_NC5
J 0
(1965 -4215);
DISPLAY 0.638298 (1965 -4215);
PAINT WHITE (1965 -4215);
WIRE 16 -1 (1825 -4125)(2450 -4125);
FORCEPROP 2 LAST SIG_NAME NC_INA230_5_NC3
J 0
(1965 -4115);
DISPLAY 0.638298 (1965 -4115);
PAINT WHITE (1965 -4115);
WIRE 16 -1 (725 -3425)(725 -3300);
WIRE 16 -1 (725 -3300)(975 -3300);
WIRE 16 -1 (975 -3300)(975 -3875);
WIRE 16 -1 (975 -3875)(1025 -3875);
WIRE 16 -1 (-875 -3850)(125 -3850);
WIRE 16 -1 (125 -3625)(125 -3850);
WIRE 16 -1 (925 -3850)(125 -3850);
FORCEPROP 2 LAST SIG_NAME INA230_5_A1
J 0
(315 -3840);
DISPLAY 0.638298 (315 -3840);
PAINT WHITE (315 -3840);
WIRE 16 -1 (925 -3850)(925 -3975);
WIRE 16 -1 (925 -3975)(1025 -3975);
WIRE 16 -1 (-875 -3925)(-175 -3925);
WIRE 16 -1 (-175 -3625)(-175 -3925);
WIRE 16 -1 (875 -3925)(-175 -3925);
FORCEPROP 2 LAST SIG_NAME INA230_5_A0
J 0
(315 -3915);
DISPLAY 0.638298 (315 -3915);
PAINT WHITE (315 -3915);
WIRE 16 -1 (875 -3925)(875 -4025);
WIRE 16 -1 (875 -4025)(1025 -4025);
WIRE 16 -1 (-75 -4125)(1025 -4125);
FORCEPROP 2 LAST SIG_NAME SMB_INA230_5_3V3AUX_SCL_R1
J 0
(240 -4115);
DISPLAY 0.680851 (240 -4115);
PAINT WHITE (240 -4115);
WIRE 16 -1 (-75 -4175)(1025 -4175);
FORCEPROP 2 LAST SIG_NAME SMB_INA230_5_3V3AUX_SDA_R1
J 0
(240 -4165);
DISPLAY 0.680851 (240 -4165);
PAINT WHITE (240 -4165);
WIRE 16 -1 (-1950 -3850)(-1950 -3725);
WIRE 16 -1 (-1950 -3725)(-1700 -3725);
WIRE 16 -1 (-1700 -3725)(-1700 -4275);
WIRE 16 -1 (1025 -4275)(-1700 -4275);
WIRE 16 -1 (200 -4725)(-50 -4725);
WIRE 16 -1 (200 -4775)(200 -4725);
WIRE 16 -1 (800 -4725)(200 -4725);
FORCEPROP 2 LAST SIG_NAME VSENSE_P12V_INA230_5_INP
J 0
(215 -4715);
DISPLAY 0.510638 (215 -4715);
PAINT WHITE (215 -4715);
WIRE 16 -1 (800 -4725)(800 -4325);
WIRE 16 -1 (800 -4325)(1025 -4325);
WIRE 16 -1 (-50 -5000)(200 -5000);
WIRE 16 -1 (200 -4975)(200 -5000);
WIRE 16 -1 (900 -5000)(200 -5000);
FORCEPROP 2 LAST SIG_NAME VSENSE_P12V_INA230_5_INN
J 0
(240 -4990);
DISPLAY 0.510638 (240 -4990);
PAINT WHITE (240 -4990);
WIRE 16 -1 (900 -5000)(900 -4375);
WIRE 16 -1 (900 -4375)(1025 -4375);
WIRE 16 -1 (2800 -1725)(3825 -1725);
FORCEPROP 2 LAST SIG_NAME M2_0_P3V3_ADC_ALERT
J 0
(3190 -1715);
DISPLAY 0.638298 (3190 -1715);
PAINT WHITE (3190 -1715);
WIRE 16 -1 (1700 -2175)(1825 -2175);
WIRE 16 2175 (2275 -1500)(2950 -1500);
WIRE 16 2175 (2950 -900)(2950 -1500);
WIRE 16 2175 (2275 -900)(2275 -1500);
WIRE 16 2175 (2275 -900)(2950 -900);
WIRE 16 -1 (1700 -1875)(2325 -1875);
FORCEPROP 2 LAST SIG_NAME NC_INA230_4_NC1
J 0
(1840 -1865);
DISPLAY 0.638298 (1840 -1865);
PAINT WHITE (1840 -1865);
WIRE 16 -1 (1700 -1925)(2325 -1925);
FORCEPROP 2 LAST SIG_NAME NC_INA230_4_NC2
J 0
(1840 -1915);
DISPLAY 0.638298 (1840 -1915);
PAINT WHITE (1840 -1915);
WIRE 16 -1 (1700 -2075)(2325 -2075);
FORCEPROP 2 LAST SIG_NAME NC_INA230_4_NC5
J 0
(1840 -2065);
DISPLAY 0.638298 (1840 -2065);
PAINT WHITE (1840 -2065);
WIRE 16 -1 (850 -1725)(900 -1725);
WIRE 16 -1 (850 -1150)(850 -1725);
WIRE 16 -1 (600 -1275)(600 -1150);
WIRE 16 -1 (600 -1150)(850 -1150);
WIRE 16 -1 (-950 -1750)(-225 -1750);
WIRE 16 -1 (-225 -1425)(-225 -1750);
WIRE 16 -1 (-225 -1750)(750 -1750);
FORCEPROP 2 LAST SIG_NAME INA230_4_A0
J 0
(190 -1740);
DISPLAY 0.638298 (190 -1740);
PAINT WHITE (190 -1740);
WIRE 16 -1 (750 -1750)(750 -1875);
WIRE 16 -1 (750 -1875)(900 -1875);
WIRE 16 -1 (-200 -1975)(900 -1975);
FORCEPROP 2 LAST SIG_NAME SMB_INA230_4_3V3AUX_SCL_R1
J 0
(115 -1965);
DISPLAY 0.680851 (115 -1965);
PAINT WHITE (115 -1965);
WIRE 16 -1 (-200 -2025)(900 -2025);
FORCEPROP 2 LAST SIG_NAME SMB_INA230_4_3V3AUX_SDA_R1
J 0
(115 -2015);
DISPLAY 0.680851 (115 -2015);
PAINT WHITE (115 -2015);
WIRE 16 -1 (75 -2575)(-175 -2575);
WIRE 16 -1 (75 -2625)(75 -2575);
WIRE 16 -1 (675 -2575)(75 -2575);
FORCEPROP 2 LAST SIG_NAME VSENSE_P12V_INA230_4_INP
J 0
(90 -2565);
DISPLAY 0.510638 (90 -2565);
PAINT WHITE (90 -2565);
WIRE 16 -1 (675 -2575)(675 -2175);
WIRE 16 -1 (675 -2175)(900 -2175);
WIRE 16 -1 (-175 -2850)(75 -2850);
WIRE 16 -1 (75 -2825)(75 -2850);
WIRE 16 -1 (775 -2850)(75 -2850);
FORCEPROP 2 LAST SIG_NAME VSENSE_P12V_INA230_4_INN
J 0
(115 -2840);
DISPLAY 0.510638 (115 -2840);
PAINT WHITE (115 -2840);
WIRE 16 -1 (775 -2850)(775 -2225);
WIRE 16 -1 (775 -2225)(900 -2225);
WIRE 16 -1 (3375 375)(4475 375);
FORCEPROP 2 LAST SIG_NAME OCP_V3_2_P3V3_ADC_ALERT
J 0
(3765 385);
DISPLAY 0.638298 (3765 385);
PAINT WHITE (3765 385);
WIRE 16 2175 (2875 1175)(3550 1175);
WIRE 16 2175 (3550 1175)(3550 575);
WIRE 16 2175 (2875 1175)(2875 575);
WIRE 16 2175 (2875 575)(3550 575);
WIRE 16 -1 (-1650 400)(-1650 525);
WIRE 16 -1 (-1650 525)(-1400 525);
WIRE 16 -1 (-1400 525)(-1400 -25);
WIRE 16 -1 (1325 -25)(-1400 -25);
WIRE 16 -1 (200 75)(1325 75);
FORCEPROP 2 LAST SIG_NAME SMB_INA230_3_3V3AUX_SDA_R1
J 0
(515 85);
DISPLAY 0.680851 (515 85);
PAINT WHITE (515 85);
WIRE 16 -1 (525 250)(525 125);
WIRE 16 -1 (525 125)(1325 125);
FORCEPROP 2 LAST SIG_NAME SMB_INA230_3_3V3AUX_SCL_R1
J 0
(540 135);
DISPLAY 0.680851 (540 135);
PAINT WHITE (540 135);
WIRE 16 -1 (200 125)(525 125);
WIRE 16 -1 (-425 525)(525 525);
FORCEPROP 2 LAST SIG_NAME INA230_3_A0
J 0
(365 535);
DISPLAY 0.638298 (365 535);
PAINT WHITE (365 535);
WIRE 16 -1 (525 450)(525 525);
WIRE 16 -1 (525 525)(925 525);
WIRE 16 -1 (925 525)(925 225);
WIRE 16 -1 (925 225)(1325 225);
WIRE 16 -1 (-425 600)(1000 600);
FORCEPROP 2 LAST SIG_NAME INA230_3_A1
J 0
(390 610);
DISPLAY 0.638298 (390 610);
PAINT WHITE (390 610);
WIRE 16 -1 (1000 600)(1000 275);
WIRE 16 -1 (1000 275)(1325 275);
WIRE 16 -1 (1275 375)(1325 375);
WIRE 16 -1 (1275 950)(1275 375);
WIRE 16 -1 (1025 825)(1025 950);
WIRE 16 -1 (1025 950)(1275 950);
WIRE 16 -1 (-2150 -4525)(-2325 -4525);
WIRE 16 -1 (-2325 -4525)(-2325 -5000);
WIRE 16 -1 (-2325 -5000)(-250 -5000);
WIRE 16 -1 (-1075 -3850)(-1400 -3850);
WIRE 16 -1 (-1400 -3850)(-1400 -3925);
WIRE 16 -1 (-1400 -3925)(-1075 -3925);
WIRE 16 -1 (-1725 -4525)(-1950 -4525);
WIRE 16 -1 (-1725 -4725)(-1725 -4525);
WIRE 16 -1 (-1725 -4725)(-250 -4725);
WIRE 16 -1 (-950 525)(-625 525);
WIRE 16 -1 (-950 600)(-950 525);
WIRE 16 -1 (-625 600)(-950 600);
WIRE 16 -1 (-1425 -275)(-1650 -275);
WIRE 16 -1 (-1425 -475)(-1425 -275);
WIRE 16 -1 (-1425 -475)(50 -475);
WIRE 16 -1 (-1150 -1675)(-1475 -1675);
WIRE 16 -1 (-1475 -1675)(-1475 -1750);
WIRE 16 -1 (-1475 -1750)(-1150 -1750);
WIRE 16 -1 (-1850 -2375)(-2050 -2375);
WIRE 16 -1 (-1850 -2575)(-1850 -2375);
WIRE 16 -1 (-1850 -2575)(-375 -2575);
WIRE 16 -1 (-225 -1225)(-225 -1150);
WIRE 16 -1 (-225 -1150)(75 -1150);
WIRE 16 -1 (75 -1150)(75 -1225);
WIRE 16 -1 (-175 -3425)(-175 -3350);
WIRE 16 -1 (-175 -3350)(125 -3350);
WIRE 16 -1 (125 -3350)(125 -3425);
WIRE 16 -1 (-1025 125)(0 125);
FORCEPROP 2 LAST SIG_NAME SMB_INA230_3_3V3AUX_SCL_R
J 0
(-1035 135);
DISPLAY 0.680851 (-1035 135);
PAINT WHITE (-1035 135);
WIRE 16 -1 (-1025 75)(0 75);
FORCEPROP 2 LAST SIG_NAME SMB_INA230_3_3V3AUX_SDA_R
J 0
(-1035 85);
DISPLAY 0.680851 (-1035 85);
PAINT WHITE (-1035 85);
WIRE 16 -1 (-1325 -4175)(-275 -4175);
FORCEPROP 2 LAST SIG_NAME SMB_INA230_5_3V3AUX_SDA_R
J 0
(-1260 -4165);
DISPLAY 0.680851 (-1260 -4165);
PAINT WHITE (-1260 -4165);
WIRE 16 -1 (-1450 -1975)(-400 -1975);
FORCEPROP 2 LAST SIG_NAME SMB_INA230_4_3V3AUX_SCL_R
J 0
(-1385 -1965);
DISPLAY 0.680851 (-1385 -1965);
PAINT WHITE (-1385 -1965);
WIRE 16 -1 (-1450 -2025)(-400 -2025);
FORCEPROP 2 LAST SIG_NAME SMB_INA230_4_3V3AUX_SDA_R
J 0
(-1385 -2015);
DISPLAY 0.680851 (-1385 -2015);
PAINT WHITE (-1385 -2015);
WIRE 16 -1 (-1325 -4125)(-275 -4125);
FORCEPROP 2 LAST SIG_NAME SMB_INA230_5_3V3AUX_SCL_R
J 0
(-1260 -4115);
DISPLAY 0.680851 (-1260 -4115);
PAINT WHITE (-1260 -4115);
DOT 1 (-2325 -4525);
DOT 1 (-1850 -2375);
DOT 1 (975 -3300);
DOT 1 (125 -3350);
DOT 1 (-175 -3925);
DOT 1 (200 -4725);
DOT 1 (200 -5000);
DOT 1 (-1400 -3925);
DOT 1 (-1725 -4525);
DOT 1 (850 -1150);
DOT 1 (75 -1150);
DOT 1 (75 -1675);
DOT 1 (75 -2575);
DOT 1 (75 -2850);
DOT 1 (-225 -1750);
DOT 1 (-2450 -2375);
DOT 1 (1275 950);
DOT 1 (525 525);
DOT 1 (525 125);
DOT 1 (-950 525);
DOT 1 (500 -475);
DOT 1 (500 -750);
DOT 1 (-1400 525);
DOT 1 (-1425 -275);
DOT 1 (-2025 -275);
DOT 1 (-1475 -1750);
DOT 1 (125 -3850);
DOT 1 (-1700 -3725);
DOT 1 (-1825 -1575);
DOT 1 (2250 -125);
DOT 1 (3075 375);
DOT 1 (1825 -2225);
DOT 1 (2500 -1725);
DOT 1 (1950 -4375);
DOT 1 (2575 -3875);
FORCENOTE
ADDRESS : 0X88
(850 -2425) 0;
DISPLAY LEFT (850 -2425);
DISPLAY 1.340425 (850 -2425);
PAINT WHITE (850 -2425);
FORCENOTE
20211130 ADD R4090,R4091,R4092 PU TO P3V3_AUX
(1575 -875) 0;
DISPLAY LEFT (1575 -875);
DISPLAY 1.276596 (1575 -875);
PAINT PINK (1575 -875);
FORCENOTE
20210929 MODIFY FOR GT
(-3775 975) 0;
DISPLAY LEFT (-3775 975);
DISPLAY 2.510638 (-3775 975);
PAINT PINK (-3775 975);
FORCENOTE
ADDRESS : 0X8A
(950 -4575) 0;
DISPLAY LEFT (950 -4575);
DISPLAY 1.340425 (950 -4575);
PAINT WHITE (950 -4575);
FORCENOTE
ADDRESS : 0X86
(1250 -325) 0;
DISPLAY LEFT (1250 -325);
DISPLAY 1.340425 (1250 -325);
PAINT WHITE (1250 -325);
QUIT
